G04 ================== begin FILE IDENTIFICATION RECORD ==================*
G04 Layout Name:  DA0T6MTH8C0_t6m_tray_bp_c_brd_103112_274.brd*
G04 Film Name:    bot.art*
G04 File Format:  Gerber RS274X*
G04 File Origin:  Cadence Allegro 16.3-S048*
G04 Origin Date:  Tue Nov 26 11:26:40 2013*
G04 *
G04 Layer:  DRAWING FORMAT/TITLE_BLOCK*
G04 Layer:  VIA CLASS/BOTTOM*
G04 Layer:  PIN/BOTTOM*
G04 Layer:  MANUFACTURING/PHOTOPLOT_OUTLINE*
G04 Layer:  ETCH/BOTTOM*
G04 Layer:  DRAWING FORMAT/TITLE_DATA_BOT*
G04 *
G04 Offset:    (0.00 0.00)*
G04 Mirror:    No*
G04 Mode:      Positive*
G04 Rotation:  0*
G04 FullContactRelief:  No*
G04 UndefLineWidth:     6.00*
G04 ================== end FILE IDENTIFICATION RECORD ====================*
%FSLAX25Y25*MOIN*%
%IR0*IPPOS*OFA0.00000B0.00000*MIA0B0*SFA1.00000B1.00000*%
%ADD24C,.02*%
%ADD10C,.03*%
%ADD19C,.04*%
%ADD35C,.051*%
%ADD22C,.042*%
%ADD31C,.061*%
%ADD16C,.043*%
%ADD30C,.053*%
%ADD21C,.026*%
%ADD34C,.036*%
%ADD23C,.054*%
%ADD17C,.063*%
%ADD15R,.032X.197*%
%ADD27C,.046*%
%ADD41C,.092*%
%ADD11C,.066*%
%ADD39R,.051X.051*%
%ADD33C,.049*%
%ADD28C,.085*%
%ADD38R,.036X.036*%
%ADD18R,.063X.063*%
%ADD29R,.046X.046*%
%ADD13R,.066X.066*%
%ADD42R,.103X.426*%
%ADD36C,.12*%
%ADD25C,.213*%
%ADD12C,.142*%
%ADD32O,.038X.063*%
%ADD37C,.128*%
%ADD26C,.228*%
%ADD14C,.138*%
%ADD40C,.139*%
%ADD20R,.373X.248*%
%ADD43C,.0114*%
%ADD44C,.006*%
%ADD45C,.007*%
%ADD46C,.0058*%
%ADD47C,.0096*%
%ADD53C,.03004*%
%ADD49C,.05004*%
%ADD52C,.03604*%
%ADD57C,.06404*%
%ADD54C,.07304*%
%ADD59C,.05604*%
%ADD56C,.07604*%
%ADD60C,.09606*%
%ADD50C,.1601*%
%ADD58C,.13006*%
%ADD51C,.16024*%
%ADD48C,.1822*%
%ADD61C,.11705*%
%ADD62C,.11707*%
%ADD55R,.07604X.07604*%
G75*
%LPD*%
G75*
G36*
G01X0Y42126D02*
G02X35434I17717J0D01*
G01Y18504D01*
G02X0I-17717J0D01*
G01Y42126D01*
G37*
G36*
G01X1112369Y7000D02*
G02X1090861I-10754J11504D01*
G01X806700D01*
X802549Y11151D01*
Y49451D01*
X785200Y66800D01*
Y118200D01*
X777615Y125785D01*
G02X778187Y127483I707J707D01*
G03X772779Y132892I-648J4760D01*
G02X771081Y132319I-991J134D01*
G01X765100Y138300D01*
X650300D01*
X645581Y133581D01*
Y109081D01*
X621700Y85200D01*
X565802D01*
G02X565002Y86800I0J1000D01*
G03X562598I-1202J900D01*
G02X561798Y85200I-800J-600D01*
G01X529500D01*
X520825Y93875D01*
G02X520771Y95231I707J707D01*
G03X518564Y97996I-1371J1169D01*
G02X517100Y98882I-464J886D01*
G01Y130800D01*
X507200Y140700D01*
Y155400D01*
X504200Y158400D01*
X472800D01*
X465500Y151100D01*
Y102312D01*
X465409Y102114D01*
X465325Y102042D01*
G03Y99758I975J-1142D01*
G01X465409Y99686D01*
X465500Y99488D01*
Y89961D01*
G03X464870Y85438I700J-2403D01*
G03X465500Y80828I1230J-2180D01*
G01Y68800D01*
X454800Y58100D01*
X434527D01*
G02X434035Y58509I0J500D01*
G03X430493Y61456I-3542J-656D01*
G03X427124Y58530I0J-3403D01*
G02X426629Y58100I-495J70D01*
G01X414000D01*
X398500Y42600D01*
Y29000D01*
X395800Y26300D01*
Y16300D01*
X385500Y6000D01*
X40576D01*
X38100Y8476D01*
Y25047D01*
G02X39460Y25980I1000J0D01*
G03Y33076I1367J3548D01*
G02X38100Y34009I-360J933D01*
G01Y50000D01*
X24600Y63500D01*
X7000D01*
X3100Y67400D01*
Y108310D01*
G02X1968Y114173I14616J5863D01*
G01Y137795D01*
G02X33464I15748J0D01*
G01Y136336D01*
X35969Y133831D01*
X40795D01*
G02X41726Y133485I163J-987D01*
G03X48054Y136777I2802J2342D01*
G01X48019Y136907D01*
X48088Y137165D01*
X50552Y139628D01*
X67511D01*
X67614Y139578D01*
G03X69580Y139838I786J1622D01*
G02X70942Y139789I655J-756D01*
G01X87702Y123028D01*
X93339D01*
X95239Y121128D01*
X109351D01*
X111041Y122818D01*
X113065D01*
G02X113898Y121266I0J-1000D01*
G03X116902I1502J-996D01*
G02X117735Y122818I833J552D01*
G01X118911D01*
X119014Y122768D01*
G03X121601Y124342I786J1622D01*
G02X122101Y124828I500J-14D01*
G01X124111D01*
X124214Y124778D01*
G03X126566Y127292I786J1622D01*
G01X126500Y127407D01*
Y139338D01*
G02X127985Y140213I1000J0D01*
G03Y144587I1215J2187D01*
G02X126500Y145462I-485J875D01*
G01Y146713D01*
X126747Y146995D01*
X126933Y147020D01*
G03X126646Y152002I-333J2480D01*
G01X126445Y152005D01*
X123650Y154800D01*
Y201950D01*
X124900Y203200D01*
X160926D01*
G02X161426Y202700I0J-500D01*
G01Y178934D01*
X163592D01*
Y202700D01*
G02X164092Y203200I500J0D01*
G01X199800D01*
X201000Y202000D01*
Y176400D01*
X197100Y172500D01*
Y165100D01*
X203200Y159000D01*
X224500D01*
X229500Y164000D01*
Y190300D01*
X237200Y198000D01*
X302936D01*
G02X325490I11277J-10992D01*
G01X367200D01*
X376300Y188900D01*
X446200D01*
X455100Y197800D01*
X518000D01*
X526800Y189000D01*
X596000D01*
X604300Y197300D01*
X623200D01*
X631100Y189400D01*
X804500D01*
X813200Y198100D01*
X814845D01*
G02X837203I11179J-11092D01*
G01X1173113D01*
G02X1195471I11179J-11092D01*
G01X1233600D01*
X1243550Y188150D01*
X1314500D01*
X1325150Y198800D01*
X1386900D01*
X1397500Y188200D01*
X1464900D01*
X1473100Y196400D01*
X1494100D01*
X1499800Y190700D01*
X1671600D01*
X1673500Y188800D01*
Y172000D01*
X1665600Y164100D01*
Y124000D01*
X1678400Y111200D01*
Y78700D01*
X1675900Y76200D01*
X1653800D01*
X1651800Y78200D01*
Y126200D01*
X1650785Y127215D01*
G02X1650825Y128666I708J707D01*
G03X1644041Y135451I-3207J3577D01*
G02X1642589Y135411I-745J667D01*
G01X1637500Y140500D01*
X1525300D01*
X1499100Y114300D01*
Y90600D01*
X1494000Y85500D01*
X1399600D01*
X1392809Y92291D01*
X1392800Y92484D01*
G03X1391084Y94200I-1800J-84D01*
G01X1390891Y94209D01*
X1390619Y94481D01*
G02X1390817Y96049I707J707D01*
G03X1388149Y98026I-917J1551D01*
G01X1388116Y97890D01*
X1388017Y97790D01*
G02X1387310I-353J354D01*
G01X1386900Y98200D01*
Y149200D01*
X1378000Y158100D01*
X1342400D01*
X1331900Y147600D01*
Y82967D01*
G03Y82833I1500J-67D01*
G01Y82031D01*
G02X1330925Y81873I-500J-1D01*
G03X1330340Y80155I-1425J-473D01*
G02X1331900Y79326I560J-829D01*
G01Y74300D01*
X1317800Y60200D01*
X1303527D01*
G02X1303167Y60353I0J500D01*
G03X1300573Y61456I-2594J-2499D01*
G01X1300571D01*
G03X1298071Y60361I0J-3402D01*
G02X1297704Y60200I-368J339D01*
G01X1278300D01*
X1265500Y47400D01*
Y28600D01*
X1243900Y7000D01*
X1112369D01*
G37*
G36*
G01X110115Y138631D02*
G03X108114Y138922I-1215J-1331D01*
G01X108011Y138872D01*
X95372D01*
X75672Y158572D01*
X53509D01*
X49141Y162940D01*
X46700D01*
G02X46200Y163440I0J500D01*
G01Y202600D01*
X47784Y204184D01*
X80936D01*
G02X81436Y203684I0J-500D01*
G01Y178934D01*
X83592D01*
Y203692D01*
G02X84092Y204192I499J0D01*
G01X84358D01*
X84368Y204184D01*
X120616D01*
X121426Y203374D01*
Y178934D01*
X121650Y178710D01*
Y140950D01*
X119200Y138500D01*
X110452D01*
G02X110115Y138631I0J500D01*
G37*
G36*
G01X398483Y23597D02*
G03I-693J0D01*
G37*
G36*
G01Y19497D02*
G03I-693J0D01*
G37*
G36*
G01X408883Y23497D02*
G03I-693J0D01*
G37*
G36*
G01Y19897D02*
G03I-693J0D01*
G37*
G36*
G01X446683Y38397D02*
G03I-693J0D01*
G37*
G36*
G01Y33897D02*
G03I-693J0D01*
G37*
G36*
G01X456083Y33997D02*
G03I-693J0D01*
G37*
G36*
G01Y38597D02*
G03I-693J0D01*
G37*
G36*
G01X466283Y55897D02*
G03I-693J0D01*
G37*
G36*
G01X475183Y3897D02*
G03I-693J0D01*
G37*
G36*
G01X490883Y3997D02*
G03I-693J0D01*
G37*
G36*
G01X507883Y4197D02*
G03I-693J0D01*
G37*
G36*
G01X521583Y22497D02*
G03I-693J0D01*
G37*
G36*
G01X526283Y22597D02*
G03I-693J0D01*
G37*
G36*
G01Y13897D02*
G03I-693J0D01*
G37*
G36*
G01X521483Y13797D02*
G03I-693J0D01*
G37*
G36*
G01X567783Y20497D02*
G03I-693J0D01*
G37*
G36*
G01X576583Y20797D02*
G03I-693J0D01*
G37*
G36*
G01X576483Y24297D02*
G03I-693J0D01*
G37*
G36*
G01X567683Y24397D02*
G03I-693J0D01*
G37*
G36*
G01X648983Y55597D02*
G03I-693J0D01*
G37*
G36*
G01X652183Y94697D02*
G03I-693J0D01*
G37*
G36*
G01X651783Y91097D02*
G03I-693J0D01*
G37*
G36*
G01X655883Y4097D02*
G03I-693J0D01*
G37*
G36*
G01X662283Y75897D02*
G03I-693J0D01*
G37*
G36*
G01X665783Y55897D02*
G03I-693J0D01*
G37*
G36*
G01X668183Y126197D02*
G03I-693J0D01*
G37*
G36*
G01X689483Y4097D02*
G03I-693J0D01*
G37*
G36*
G01X682283Y55497D02*
G03I-693J0D01*
G37*
G36*
G01X699083Y90297D02*
G03I-693J0D01*
G37*
G36*
G01X686283Y133197D02*
G03I-693J0D01*
G37*
G36*
G01X681583D02*
G03I-693J0D01*
G37*
G36*
G01X724183Y118897D02*
G03I-693J0D01*
G37*
G36*
G01X723083Y102297D02*
G03I-693J0D01*
G37*
G36*
G01X731583Y108897D02*
G03I-693J0D01*
G37*
G36*
G01X754983Y121397D02*
G03I-693J0D01*
G37*
G36*
G01X764683Y124697D02*
G03I-693J0D01*
G37*
G36*
G01X767913Y42126D02*
G02X799409I15748J0D01*
G01Y18504D01*
G02X767913I-15748J0D01*
G01Y42126D01*
G37*
G36*
G01X775283Y90297D02*
G03I-693J0D01*
G37*
G36*
G01X1268383Y22897D02*
G03I-693J0D01*
G37*
G36*
G01Y19697D02*
G03I-693J0D01*
G37*
G36*
G01X1279383Y19797D02*
G03I-693J0D01*
G37*
G36*
G01Y22997D02*
G03I-693J0D01*
G37*
G36*
G01X1316562Y38197D02*
G03I-693J0D01*
G37*
G36*
G01X1316662Y33897D02*
G03I-693J0D01*
G37*
G36*
G01X1325962Y38597D02*
G03I-693J0D01*
G37*
G36*
G01Y33797D02*
G03I-693J0D01*
G37*
G36*
G01X1335983Y55597D02*
G03I-693J0D01*
G37*
G36*
G01X1361283Y3997D02*
G03I-693J0D01*
G37*
G36*
G01X1345383Y4097D02*
G03I-693J0D01*
G37*
G36*
G01X1376983Y3997D02*
G03I-693J0D01*
G37*
G36*
G01X1396362Y22597D02*
G03I-693J0D01*
G37*
G36*
G01X1391662Y22497D02*
G03I-693J0D01*
G37*
G36*
G01X1391562Y13797D02*
G03I-693J0D01*
G37*
G36*
G01X1396362Y13897D02*
G03I-693J0D01*
G37*
G36*
G01X1437183Y23897D02*
G03I-693J0D01*
G37*
G36*
G01Y20697D02*
G03I-693J0D01*
G37*
G36*
G01X1446583Y20797D02*
G03I-693J0D01*
G37*
G36*
G01X1446383Y24397D02*
G03I-693J0D01*
G37*
G36*
G01X1527883Y3797D02*
G03I-693J0D01*
G37*
G36*
G01X1518883Y55597D02*
G03I-693J0D01*
G37*
G36*
G01X1522262Y94697D02*
G03I-693J0D01*
G37*
G36*
G01X1521862Y91097D02*
G03I-693J0D01*
G37*
G36*
G01X1532362Y75897D02*
G03I-693J0D01*
G37*
G36*
G01X1535983Y55797D02*
G03I-693J0D01*
G37*
G36*
G01X1538262Y126197D02*
G03I-693J0D01*
G37*
G36*
G01X1559683Y4197D02*
G03I-693J0D01*
G37*
G36*
G01X1552483Y55697D02*
G03I-693J0D01*
G37*
G36*
G01X1569162Y90297D02*
G03I-693J0D01*
G37*
G36*
G01X1551662Y133197D02*
G03I-693J0D01*
G37*
G36*
G01X1556362D02*
G03I-693J0D01*
G37*
G36*
G01X1593583Y101697D02*
G03I-693J0D01*
G37*
G36*
G01X1593983Y118997D02*
G03I-693J0D01*
G37*
G36*
G01X1601583Y108697D02*
G03I-693J0D01*
G37*
G36*
G01X1624983Y121497D02*
G03I-693J0D01*
G37*
G36*
G01X1634862Y124297D02*
G03I-693J0D01*
G37*
G36*
G01X1652795Y42126D02*
G02X1688229I17717J0D01*
G01Y18504D01*
G02X1652795I-17717J0D01*
G01Y42126D01*
G37*
G36*
G01X1645362Y90297D02*
G03I-693J0D01*
G37*
%LPC*%
G75*
G36*
G01X1193184Y163386D02*
G02X1175400I-8892J0D01*
G01Y175572D01*
G03X1174795Y176977I-1935J0D01*
G02X1174180Y196419I9497J10031D01*
G03X1174255Y196510I-733J680D01*
G02X1194329I10037J-9502D01*
G03X1194404Y196419I808J589D01*
G02X1193789Y176977I-10112J-9411D01*
G03X1193185Y175572I1330J-1404D01*
G01X1193184Y163386D01*
G37*
G36*
G01X834916D02*
G02X817131I-8892J0D01*
G01Y164302D01*
X817132Y175572D01*
G03X816527Y176977I-1935J0D01*
G02X815912Y196419I9497J10031D01*
G03X815987Y196510I-733J680D01*
G02X836061I10037J-9502D01*
G03X836136Y196419I808J589D01*
G02X835521Y176977I-10112J-9411D01*
G03X834916Y175572I1330J-1405D01*
G01Y163386D01*
G37*
G36*
G01X323106D02*
G02X305320I-8893J0D01*
G01Y175572D01*
G03X304716Y176977I-1934J1D01*
G02X304015Y196325I9497J10031D01*
G03X304092Y196420I-737J676D01*
G02X324334I10121J-9412D01*
G03X324411Y196325I814J581D01*
G02X323710Y176977I-10198J-9317D01*
G03X323105Y175572I1330J-1405D01*
G01X323106Y163386D01*
G37*
G36*
G01X26608Y114173D02*
G02X13529Y106328I-8892J0D01*
G03X13451Y106361I-233J-442D01*
G02X8816Y114173I4265J7812D01*
G01Y126359D01*
G03X8214Y127758I-1927J0D01*
G02X27218I9502J10037D01*
G03X26616Y126359I1325J-1399D01*
G01Y119917D01*
X26608Y119909D01*
Y114173D01*
G37*
G36*
G01X85124Y100177D02*
G02X81712Y103589I-3195J217D01*
G03X82177Y104116I-34J499D01*
G02X82178Y104545I3689J206D01*
G03X81712Y105073I-499J29D01*
G02X85124Y108484I217J3195D01*
G03X85652Y108019I499J34D01*
G02X86870Y107886I214J-3688D01*
G01Y107044D01*
G03X87128Y106606I500J0D01*
G02X88120Y105632I-1261J-2276D01*
G01X88187Y105515D01*
X88418Y105382D01*
X89408D01*
G02X89560Y104331I-3542J-1049D01*
G02X89554Y104116I-3694J-4D01*
G03X90020Y103589I499J-28D01*
G02X86608Y100177I-217J-3195D01*
G03X86080Y100643I-499J-33D01*
G02X85652I-214J3688D01*
G03X85124Y100177I-29J-499D01*
G37*
G36*
G01X1285206Y85715D02*
G02X1284321Y83725I503J-1415D01*
G03X1283062Y84285I-924J-382D01*
G02X1281151Y85178I-503J1415D01*
G03X1279892Y85777I-938J-348D01*
G02X1280818Y87722I-482J1423D01*
G03X1282077Y87123I938J348D01*
G02X1283947Y86275I482J-1423D01*
G03X1285206Y85715I924J382D01*
G37*
G36*
G01X414758Y81923D02*
G02X414611Y79597I872J-1223D01*
G03X413352Y79677I-679J-735D01*
G02X413499Y82003I-872J1223D01*
G03X414758Y81923I679J735D01*
G37*
G36*
G01X125367Y81132D02*
G02X124068Y79833I191J-1490D01*
G03X122949Y80952I-992J127D01*
G02X124248Y82251I-191J1490D01*
G03X125367Y81132I992J-127D01*
G37*
G36*
G01X1290317Y78037D02*
G02X1289292Y79838I-1458J363D01*
G03X1290550Y80555I287J958D01*
G02X1291575Y78754I1458J-363D01*
G03X1290317Y78037I-287J-958D01*
G37*
G36*
G01X85124Y68681D02*
G02X81712Y72093I-3195J217D01*
G03X82177Y72620I-34J499D01*
G02X82178Y73049I3689J206D01*
G03X81712Y73577I-499J29D01*
G02X78898Y77806I217J3195D01*
G03X77952Y79128I-946J322D01*
G01X77049D01*
X76149Y80028D01*
X48596D01*
G03X47722Y78543I0J-1000D01*
G02X41334I-3194J-1771D01*
G03X40460Y80028I-874J485D01*
G01X31449D01*
X26349Y85128D01*
X13695D01*
X10545Y88278D01*
X10282Y88346D01*
X10150Y88307D01*
G02X12739Y90896I-1062J3651D01*
G01X12700Y90764D01*
X12768Y90501D01*
X13579Y89689D01*
G03X15286Y90396I707J707D01*
G01Y95760D01*
X22890D01*
Y88772D01*
G03X23390Y88272I499J-1D01*
G01X27651D01*
X32751Y83172D01*
X77451D01*
X78351Y82272D01*
X78737D01*
G03X79168Y83025I0J500D01*
G02X82400Y87813I2761J1621D01*
G01Y88100D01*
X89900D01*
X90122Y87838D01*
X90319Y87806D01*
G02X92564Y83025I-516J-3160D01*
G03X92995Y82272I431J-253D01*
G01X93551D01*
X99000Y76822D01*
X107600D01*
X109414Y75009D01*
G03X110777Y74961I707J707D01*
G02X113760Y73582I1181J-1361D01*
G03X114760Y72572I1000J-10D01*
G01X121279D01*
X121360Y72600D01*
G02X121028Y69357I598J-1700D01*
G01X120909Y69428D01*
X119755D01*
G03X118757Y68490I0J-1000D01*
G02X115159I-1799J110D01*
G03X114161Y69428I-998J-62D01*
G01X110549D01*
X106298Y73680D01*
X97698D01*
X94645Y76732D01*
G03X92954Y76203I-707J-707D01*
G02X90020Y73577I-3151J569D01*
G03X89554Y73049I33J-499D01*
G02X89560Y72835I-3688J-210D01*
G02X89554Y72620I-3694J-4D01*
G03X90020Y72093I499J-28D01*
G02X86608Y68681I-217J-3195D01*
G03X86080Y69147I-499J-33D01*
G02X85652I-214J3688D01*
G03X85124Y68681I-29J-499D01*
G37*
G36*
G01X99009Y58328D02*
X42749D01*
X29226Y71852D01*
X15172D01*
X10545Y76478D01*
X10282Y76546D01*
X10150Y76507D01*
G02X12739Y79096I-1062J3651D01*
G01X12700Y78964D01*
X12768Y78701D01*
X13579Y77889D01*
G03X15286Y78596I707J707D01*
G01Y83960D01*
X22890D01*
Y76357D01*
X16319D01*
G03X15965Y75503I0J-500D01*
G01X16474Y74994D01*
X30528D01*
X39513Y66010D01*
G03X41146Y66339I707J707D01*
G02X47613Y63007I3382J-1377D01*
G03X48458Y61472I845J-535D01*
G01X97707D01*
X105218Y68982D01*
X105256Y69091D01*
G02X107549Y66798I1702J-591D01*
G01X107440Y66760D01*
X99009Y58328D01*
G37*
G36*
G01X1110508Y18504D02*
G02X1092722I-8893J0D01*
G01Y30690D01*
G03X1092118Y32095I-1934J1D01*
G02X1111112I9497J10031D01*
G03X1110508Y30690I1330J-1404D01*
G01Y18504D01*
G37*
G36*
G01X774159Y32089D02*
G02X793163I9502J10037D01*
G03X792561Y30690I1325J-1399D01*
G01Y18504D01*
G02X774761I-8900J0D01*
G01Y30690D01*
G03X774159Y32089I-1927J0D01*
G37*
G54D53*
X526612Y142000D03*
X367200Y124000D03*
X1238900Y123300D03*
X1474200Y106600D03*
X1472400Y102700D03*
X604400Y96000D03*
X403032Y89532D03*
X549174Y89400D03*
X1273111Y89100D03*
X409331Y88600D03*
X1429400Y88500D03*
X1434200Y88100D03*
X412300Y85600D03*
X117158Y82542D03*
X112158Y82342D03*
X406181Y82300D03*
X106958Y82142D03*
X399882Y79318D03*
X1276260Y79000D03*
X1269961Y78400D03*
X421929D03*
G54D49*
X1157000Y189800D03*
X1127000D03*
X1097000D03*
X1067000D03*
X1037000D03*
X1007000D03*
X977000D03*
X947000D03*
X917000D03*
X887000D03*
X857000D03*
X350200Y181100D03*
X281000Y180700D03*
X252800Y179900D03*
X350000Y161800D03*
X280000Y159800D03*
X252200Y159400D03*
X1155400Y152400D03*
X1125400D03*
X1095400D03*
X1065400D03*
X1035400D03*
X1005400D03*
X975400D03*
X945400D03*
X915400D03*
X885400D03*
X855400D03*
X267700Y145200D03*
X300300Y140000D03*
X1108300Y128100D03*
X1078300D03*
X1048300D03*
X1018300D03*
X988300D03*
X958300D03*
X928300D03*
X898300D03*
X868300D03*
X838300D03*
X158200Y102400D03*
X129200Y101300D03*
X307800Y101100D03*
X281800Y100900D03*
X216400Y100500D03*
X251600Y100100D03*
X273300Y94900D03*
X131400Y91300D03*
X139800Y90200D03*
X161800Y86800D03*
X989700Y86500D03*
X959700D03*
X929700D03*
X899700D03*
X869700D03*
X839700D03*
X809700D03*
X181400Y84700D03*
X1151900Y84100D03*
X1121900D03*
X1091900D03*
X1061900D03*
X1031900D03*
X254400Y74300D03*
X174300Y73300D03*
X144100Y72900D03*
X206700Y72700D03*
X283600Y69500D03*
X159800Y65100D03*
X1147100Y64500D03*
X1120900D03*
X195600Y64100D03*
X138700Y63500D03*
X257800Y51200D03*
X168100Y48400D03*
X197800Y48000D03*
X1073000Y45500D03*
X1043000D03*
X813700Y43900D03*
X123900Y41000D03*
X244900Y36600D03*
X184100D03*
X268300Y36200D03*
X214700Y35800D03*
X151500D03*
X121200Y33900D03*
X229200Y30900D03*
X197800D03*
X102500Y29400D03*
X90200Y22400D03*
X194400Y20200D03*
X76900D03*
X225800Y19600D03*
X165600Y19400D03*
X107200Y19300D03*
X254400Y19200D03*
X959000Y18000D03*
X1063700Y15300D03*
G54D52*
X626173Y148400D03*
X1495800Y147800D03*
X1487600Y147000D03*
X617949D03*
X1211200Y144900D03*
X1217405Y143895D03*
X347350Y143750D03*
X346906Y137693D03*
X1219600Y129400D03*
X1238100Y127900D03*
X1492042Y126358D03*
X345900Y125100D03*
X1219400Y123900D03*
X350700Y121642D03*
X622200Y120258D03*
X1226900Y119561D03*
X1492300Y117558D03*
X102590Y115680D03*
X357800Y114657D03*
X128600Y114510D03*
X1226900Y114043D03*
X622658Y112158D03*
X132500Y110100D03*
X1484800Y109357D03*
X357600Y108561D03*
X1227000Y108361D03*
X604200Y107400D03*
X615500Y105157D03*
X1484900Y103257D03*
X356861Y102961D03*
X1227100Y102861D03*
X452000Y102200D03*
X615500Y100157D03*
X1395200Y99500D03*
X525700Y99300D03*
X1323000Y99239D03*
X1485000Y98057D03*
X452100Y97000D03*
X615600Y95139D03*
X1484700Y93057D03*
X1321400Y92800D03*
X453900Y92300D03*
X614900Y90157D03*
X1322500Y87800D03*
X453300Y86800D03*
X1321500Y82600D03*
X451100Y81400D03*
G54D57*
X89803Y92520D03*
X81929D03*
G54D54*
X44528Y124016D03*
Y112205D03*
Y100394D03*
Y88583D03*
Y53150D03*
Y41339D03*
G54D59*
X1237480Y59054D03*
X1229606D03*
X367402D03*
X359528D03*
X1237480Y51180D03*
X1229606D03*
X367402D03*
X359528D03*
X1237480Y43306D03*
X1229606D03*
X367402D03*
X359528D03*
X1237480Y27558D03*
X1229606D03*
X367402D03*
X359528D03*
X1237480Y19684D03*
X1229606D03*
X367402D03*
X359528D03*
X1237480Y11810D03*
X1229606D03*
X367402D03*
X359528D03*
G54D56*
X109288Y103958D03*
Y92458D03*
G54D60*
X1262872Y56654D03*
X392793Y56653D03*
G54D50*
X1378938Y176650D03*
X508859D03*
G54D58*
X1009800Y81300D03*
X109500Y41000D03*
G54D51*
X1333938Y176650D03*
X463859D03*
G54D48*
X17717Y18504D03*
X1670512D03*
G54D61*
X1221732Y37400D03*
G54D62*
X351654D03*
G54D55*
X119288Y103958D03*
Y92458D03*
%LPD*%
G75*
G54D10*
X8221Y28000D03*
Y9008D03*
X4287Y18504D03*
X17717Y5074D03*
X27213Y28000D03*
X31147Y18504D03*
X27213Y9008D03*
X17717Y31934D03*
X1661016Y28000D03*
Y9008D03*
X1657082Y18504D03*
X1670512Y5074D03*
X1680008Y28000D03*
X1683942Y18504D03*
X1680008Y9008D03*
X1670512Y31934D03*
G54D20*
X62521Y191536D03*
X102521D03*
X142521D03*
X182521D03*
G54D11*
X9088Y80158D03*
Y91958D03*
X109288Y92458D03*
Y103958D03*
G54D12*
X17717Y18504D03*
X1670512D03*
G54D21*
X68400Y141200D03*
X64500Y165200D03*
X99100Y127470D03*
X89400Y165300D03*
X102400Y59600D03*
X111958Y73600D03*
X121958Y70900D03*
X116958Y68600D03*
X106958Y68500D03*
X102590Y115680D03*
X115400Y120270D03*
X107390Y125110D03*
X119800Y124390D03*
X108900Y137300D03*
X114300Y134900D03*
X119700Y132400D03*
X111500Y129900D03*
X105800Y165400D03*
X128600Y114510D03*
X132500Y110100D03*
X125000Y126400D03*
X141400Y164800D03*
X129000D03*
X169200Y165200D03*
X155500Y164800D03*
X183300Y164700D03*
X346800Y113500D03*
X345400Y107600D03*
X346200Y102500D03*
X350700Y121642D03*
X345900Y125100D03*
X347350Y143750D03*
X346906Y137693D03*
X362500Y97100D03*
X357800Y114657D03*
X357600Y108561D03*
X356861Y102961D03*
X414900Y6500D03*
X463435Y79865D03*
X453900Y92300D03*
X453300Y86800D03*
X451100Y81400D03*
X452100Y97000D03*
X452000Y102200D03*
X488000Y89800D03*
X477630Y88900D03*
X525700Y99300D03*
X519400Y96400D03*
X520439Y91000D03*
X516500Y87442D03*
X571500Y7500D03*
X604200Y107400D03*
X614900Y90157D03*
X615600Y95139D03*
X625600Y95400D03*
X625700Y90100D03*
X615500Y100157D03*
X622658Y112158D03*
X622200Y120258D03*
X615500Y105157D03*
X626173Y148400D03*
X617949Y147000D03*
X659310Y72900D03*
X664310D03*
X654400Y92100D03*
Y97100D03*
X672638Y93290D03*
X666614Y121000D03*
X661614D03*
X671063Y125930D03*
X676063D03*
X680300Y75600D03*
X689723Y89400D03*
X689311Y96311D03*
X677638Y93290D03*
X689961Y122030D03*
X694961D03*
X680612Y129600D03*
X685612D03*
X701100Y16900D03*
X701670Y97100D03*
Y92100D03*
X740300Y87300D03*
X735807Y96593D03*
X724400Y105600D03*
X729400D03*
X730310Y115390D03*
X725310D03*
X761929Y72900D03*
X756929D03*
X752480Y92830D03*
X747480D03*
X764153Y96153D03*
X745905Y120452D03*
X750905D03*
X764803Y120330D03*
X760410Y124730D03*
X755410D03*
X778200Y92130D03*
Y97130D03*
X776032Y101968D03*
X769803Y120330D03*
X1223200Y99000D03*
X1216500Y119500D03*
X1216700Y114400D03*
X1216500Y108300D03*
X1216400Y102600D03*
X1226900Y119561D03*
Y114043D03*
X1227000Y108361D03*
X1227100Y102861D03*
X1219600Y129400D03*
X1219400Y123900D03*
X1211200Y144900D03*
X1217405Y143895D03*
X1229800Y96400D03*
X1238100Y127900D03*
X1323000Y99239D03*
X1321400Y92800D03*
X1321500Y82600D03*
X1322500Y87800D03*
X1359000Y91000D03*
X1387400Y87242D03*
X1389900Y97600D03*
X1395200Y99500D03*
X1391000Y92400D03*
X1442400Y8200D03*
X1494200Y97800D03*
X1495000Y92800D03*
X1484700Y93057D03*
X1485000Y98057D03*
X1484900Y103257D03*
X1492300Y117558D03*
X1484800Y109357D03*
X1492042Y126358D03*
X1495800Y147800D03*
X1487600Y147000D03*
X1524478Y97100D03*
Y92100D03*
X1534388Y72900D03*
X1529388D03*
X1550500Y75500D03*
X1542716Y93290D03*
X1547716D03*
X1531692Y121000D03*
X1536692D03*
X1546141Y125930D03*
X1550690Y129600D03*
X1541141Y125930D03*
X1570800Y18900D03*
X1571748Y92100D03*
Y97100D03*
X1559802Y89400D03*
X1559389Y96311D03*
X1565039Y122030D03*
X1560039D03*
X1555690Y129600D03*
X1594478Y105600D03*
X1595388Y115390D03*
X1617558Y92830D03*
X1610379Y87300D03*
X1605885Y96593D03*
X1599478Y105600D03*
X1600388Y115390D03*
X1615983Y120452D03*
X1627007Y72900D03*
X1632007D03*
X1622558Y92830D03*
X1634231Y96153D03*
X1620983Y120452D03*
X1639881Y120330D03*
X1634881D03*
X1625488Y124730D03*
X1630488D03*
X1648278Y97130D03*
Y92130D03*
X1646110Y101968D03*
G54D30*
X392776Y32264D03*
X383642Y50375D03*
Y70060D03*
Y88564D03*
X411673Y32264D03*
X430571D03*
X439744Y50375D03*
Y70060D03*
Y88564D03*
X532934Y50375D03*
Y70060D03*
Y88564D03*
X542068Y32264D03*
X560965D03*
X579863D03*
X589036Y50375D03*
Y70060D03*
Y88564D03*
X1262855Y32264D03*
X1253721Y50375D03*
Y70060D03*
Y88564D03*
X1281752Y32264D03*
X1300650D03*
X1309823Y50375D03*
Y70060D03*
Y88564D03*
X1412146Y32264D03*
X1403012Y50375D03*
Y70060D03*
Y88564D03*
X1431043Y32264D03*
X1449941D03*
X1459114Y50375D03*
Y70060D03*
Y88564D03*
G54D40*
X639283Y108622D03*
Y167677D03*
X793693Y108622D03*
Y167677D03*
X1509362Y108622D03*
Y167677D03*
X1663772Y108622D03*
Y167677D03*
G54D13*
X19088Y80158D03*
Y91958D03*
X119288Y92458D03*
Y103958D03*
G54D31*
X383642Y40532D03*
Y79902D03*
X396122Y99587D03*
X383642Y119272D03*
Y158642D03*
X417382Y99587D03*
X405964Y178327D03*
X439744Y99587D03*
Y138957D03*
Y178327D03*
X532934Y40532D03*
Y79902D03*
Y119272D03*
Y158642D03*
X545414Y99587D03*
X555256Y178327D03*
X566674Y99587D03*
X589036D03*
Y138957D03*
Y178327D03*
X1253721Y40532D03*
Y79902D03*
Y119272D03*
Y158642D03*
X1266201Y99587D03*
X1276043Y178327D03*
X1287461Y99587D03*
X1309823D03*
Y138957D03*
Y178327D03*
X1403012Y40532D03*
Y79902D03*
Y119272D03*
Y158642D03*
X1415492Y99587D03*
X1436752D03*
X1425334Y178327D03*
X1459114Y99587D03*
Y138957D03*
Y178327D03*
G54D22*
X85866Y72835D03*
Y104331D03*
G54D14*
X17716Y114173D03*
X314213Y163386D03*
X783661Y18504D03*
X826024Y163386D03*
X1101615Y18504D03*
X1184292Y163386D03*
G54D32*
X430591Y56653D03*
X579883Y56654D03*
X1300670D03*
X1449962Y56653D03*
G54D41*
X641212Y132244D03*
X791764D03*
X1511291D03*
X1661843D03*
G54D23*
X81929Y76772D03*
Y68898D03*
X89803Y76772D03*
Y68898D03*
X81929Y100394D03*
Y92520D03*
Y84646D03*
X89803Y100394D03*
Y92520D03*
Y84646D03*
X81929Y108268D03*
X89803D03*
G54D42*
X1676417Y102756D03*
G54D33*
X439744Y60217D03*
X589036D03*
X1309823D03*
X1459114D03*
G54D15*
X8741Y194095D03*
X13741D03*
X18741D03*
X23741D03*
X28741D03*
X33741D03*
G54D24*
X120500Y59400D03*
X114400Y59700D03*
X107500Y59500D03*
X122758Y82442D03*
X117158Y82542D03*
X112158Y82342D03*
X106958Y82142D03*
X125558Y79642D03*
X357600Y97000D03*
X367200Y124000D03*
X397800Y23600D03*
Y19500D03*
X398307Y35000D03*
Y46100D03*
X396732Y78932D03*
X417900Y6700D03*
X410200D03*
X404400Y6800D03*
X408200Y23500D03*
Y19900D03*
X405531Y21960D03*
X400531D03*
X400100Y13900D03*
X412800Y16200D03*
X417205Y35000D03*
X407600D03*
X407756Y46100D03*
X417205D03*
X410906D03*
X414055Y46200D03*
X412480Y80900D03*
X403032Y89532D03*
X415630Y80700D03*
X412300Y85600D03*
X421929Y78400D03*
X409331Y88600D03*
X406181Y82300D03*
X399882Y79318D03*
X426500Y35000D03*
X426654Y46100D03*
X426200Y78100D03*
X446000Y38400D03*
Y33900D03*
X455400Y34000D03*
Y38600D03*
X447880Y36200D03*
X453480D03*
X465600Y55900D03*
X466200Y87558D03*
X466100Y83258D03*
X466300Y100900D03*
X474500Y3900D03*
X490200Y4000D03*
X488800Y73700D03*
Y93800D03*
X507200Y4200D03*
X505700Y90200D03*
X511600Y108000D03*
X520900Y22500D03*
X525600Y22600D03*
Y13900D03*
X520800Y13800D03*
X523300Y15580D03*
Y20580D03*
X526612Y142000D03*
X559425Y13575D03*
X560198Y46100D03*
X556900Y35000D03*
X547599D03*
X557048Y46100D03*
X547599D03*
X558623Y79200D03*
X552324Y78500D03*
X546024Y79200D03*
X549174Y89400D03*
X575600Y7600D03*
X567500Y7300D03*
X563100Y7200D03*
X582416Y16466D03*
X567100Y20500D03*
X575900Y20800D03*
X575800Y24300D03*
X567000Y24400D03*
X573721Y22500D03*
X568721D03*
X563347Y46100D03*
X575946D03*
X566497D03*
X575800Y35000D03*
X566497D03*
X571221Y79700D03*
X568072Y81500D03*
X564922Y81900D03*
X561772Y80800D03*
X574371Y78400D03*
X563800Y87700D03*
X604400Y96000D03*
X626100Y99900D03*
X626600Y106100D03*
X648300Y55600D03*
X651500Y94700D03*
X651100Y91100D03*
X655200Y4100D03*
X661600Y75900D03*
X667200Y75700D03*
X665100Y55900D03*
X670414Y96486D03*
X658400Y102500D03*
X659390Y117490D03*
X668839Y117661D03*
X667500Y126200D03*
X688800Y4100D03*
X681600Y55500D03*
X698400Y90300D03*
X679862Y96538D03*
X678288Y122700D03*
X697185Y117385D03*
X687736Y118700D03*
X685600Y133200D03*
X680900D03*
X701732Y101968D03*
X745256Y96044D03*
X743681Y117400D03*
X731950Y111850D03*
X723500Y118900D03*
X722400Y102300D03*
X730900Y108900D03*
X753100Y75100D03*
X765600Y74800D03*
X754704Y96196D03*
X762578Y117300D03*
X753130D03*
X754300Y121400D03*
X764000Y124700D03*
X774600Y90300D03*
X772027Y117300D03*
X1218000Y99100D03*
X1238900Y123300D03*
X1273000Y6100D03*
X1270610Y21960D03*
X1267700Y22900D03*
Y19700D03*
X1268700Y14000D03*
X1268386Y35000D03*
Y46100D03*
X1266811Y78300D03*
X1273111Y89100D03*
X1269961Y78400D03*
X1276700Y5900D03*
X1280900D03*
X1285800D03*
X1278700Y19800D03*
Y23000D03*
X1275610Y21960D03*
X1289775Y11975D03*
X1296600Y35000D03*
X1277700D03*
X1287284D03*
X1296733Y46100D03*
X1287284D03*
X1277835D03*
X1284134D03*
X1280985Y46200D03*
X1295158Y79158D03*
X1292008Y80192D03*
X1288859Y78400D03*
X1279410Y87200D03*
X1285709Y84300D03*
X1276260Y79000D03*
X1282559Y85700D03*
X1315879Y38200D03*
X1315979Y33900D03*
X1317959Y36200D03*
X1323559D03*
X1325279Y38600D03*
Y33800D03*
X1335300Y55600D03*
X1340400Y90800D03*
X1333400Y82900D03*
X1329500Y81400D03*
X1335600Y96500D03*
X1360600Y4000D03*
X1344700Y4100D03*
X1358200Y69000D03*
X1358600Y73700D03*
X1345100Y105500D03*
X1376300Y4000D03*
X1371600Y86463D03*
Y96000D03*
X1395679Y22600D03*
X1390979Y22500D03*
X1390879Y13800D03*
X1395679Y13900D03*
X1393379Y20580D03*
Y15580D03*
X1433700Y8000D03*
X1429525Y13775D03*
X1417678Y46100D03*
X1427127D03*
X1417678Y35000D03*
X1427000D03*
X1433426Y46100D03*
X1430277D03*
X1416103Y78400D03*
X1422403D03*
X1434200Y88100D03*
X1435001Y81700D03*
X1431851Y80200D03*
X1428702Y79002D03*
X1429400Y88500D03*
X1438000Y8100D03*
X1446300Y8300D03*
X1436500Y23900D03*
Y20700D03*
X1445900Y20800D03*
X1445700Y24400D03*
X1443800Y22500D03*
X1438800D03*
X1454600Y17600D03*
X1446025Y46100D03*
X1436576D03*
X1445900Y35000D03*
X1436576D03*
X1444450Y78300D03*
X1441300Y79100D03*
X1438151Y81100D03*
X1472400Y102700D03*
X1474200Y106600D03*
X1494700Y111200D03*
X1494500Y102700D03*
X1527200Y3800D03*
X1518200Y55600D03*
X1521579Y94700D03*
X1521179Y91100D03*
X1537279Y75700D03*
X1531679Y75900D03*
X1535300Y55800D03*
X1549940Y96538D03*
X1540492Y96486D03*
X1528478Y102500D03*
X1548366Y122700D03*
X1538917Y117661D03*
X1529468Y117490D03*
X1550979Y133200D03*
X1537579Y126200D03*
X1559000Y4200D03*
X1551800Y55700D03*
X1568479Y90300D03*
X1571810Y101968D03*
X1557814Y118700D03*
X1567263Y117385D03*
X1555679Y133200D03*
X1592900Y101700D03*
X1593300Y119000D03*
X1615334Y96044D03*
X1613759Y117400D03*
X1602028Y111850D03*
X1600900Y108700D03*
X1635679Y74800D03*
X1623179Y75100D03*
X1624782Y96196D03*
X1623208Y117300D03*
X1642105D03*
X1632656D03*
X1624300Y121500D03*
X1634179Y124300D03*
X1644679Y90300D03*
X1676100Y78900D03*
G54D43*
G01X9088Y80158D02*
X15823Y73423D01*
X29877D01*
X43400Y59900D01*
X98358D01*
X106958Y68500D01*
G01X9088Y91958D02*
X14346Y86700D01*
X27000D01*
X32100Y81600D01*
X76800D01*
X77700Y80700D01*
X92900D01*
X98349Y75251D01*
X106949D01*
X111200Y71000D01*
X121858D01*
X121958Y70900D01*
G01X125000Y126400D02*
X121100D01*
X120600Y126900D01*
X109100D01*
X108500Y127500D01*
X105300D01*
X102900Y125100D01*
X96800D01*
X94600Y127300D01*
X89400D01*
X70560Y146140D01*
X50239D01*
X44369Y152010D01*
X32090D01*
X13741Y170359D01*
Y194095D01*
G01X119800Y124390D02*
X110390D01*
X108700Y122700D01*
X95890D01*
X93990Y124600D01*
X88353D01*
X69153Y143800D01*
X44800D01*
X43400Y142400D01*
X38300D01*
X8741Y171959D01*
Y194095D01*
G01X23741D02*
Y170159D01*
X37210Y156690D01*
X46310D01*
X51700Y151300D01*
X73119D01*
X92019Y132400D01*
X119700D01*
G01X18741Y194095D02*
Y169259D01*
X33650Y154350D01*
X45339D01*
X51089Y148600D01*
X72000D01*
X90700Y129900D01*
X111500D01*
G01X28741Y194095D02*
Y171749D01*
X41460Y159030D01*
X47518D01*
X51888Y154660D01*
X74050D01*
X93810Y134900D01*
X114300D01*
G01X68400Y141200D02*
X49901D01*
X44528Y135827D01*
G01X33741Y194095D02*
Y170059D01*
X42430Y161370D01*
X48488D01*
X52858Y157000D01*
X75021D01*
X94721Y137300D01*
X108900D01*
G54D25*
X306772Y19685D03*
Y41850D03*
X612047Y19685D03*
Y41850D03*
X1176851Y19685D03*
Y41850D03*
X1482126Y19685D03*
Y41850D03*
G54D34*
X466654Y7874D03*
Y29922D03*
Y24410D03*
Y18898D03*
Y13386D03*
Y51969D03*
Y46457D03*
Y40945D03*
Y35433D03*
X474528Y8268D03*
X482402Y7874D03*
X490276Y8268D03*
X474528Y30315D03*
X482402Y29922D03*
X490276Y30315D03*
X474528Y24803D03*
X482402Y24410D03*
X490276Y24803D03*
X474528Y19292D03*
X482402Y18898D03*
X490276Y19292D03*
X474528Y13780D03*
X482402Y13386D03*
X490276Y13780D03*
X474528Y52362D03*
X482402Y51969D03*
X490276Y52362D03*
X474528Y46851D03*
X482402Y46457D03*
X490276Y46851D03*
X474528Y41339D03*
X482402Y40945D03*
X490276Y41339D03*
X474528Y35827D03*
X482402Y35433D03*
X490276Y35827D03*
X498150Y7874D03*
Y29922D03*
X506024Y30315D03*
X498150Y24410D03*
X506024Y24803D03*
X498150Y18898D03*
X506024Y19292D03*
X498150Y13386D03*
X506024Y13780D03*
X498150Y51969D03*
X506024Y52362D03*
X498150Y46457D03*
X506024Y46851D03*
X498150Y40945D03*
X506024Y41339D03*
X498150Y35433D03*
X506024Y35827D03*
X649173Y7874D03*
Y29922D03*
Y24410D03*
Y18898D03*
Y13386D03*
Y51969D03*
Y46457D03*
Y40945D03*
Y35433D03*
X657047Y8268D03*
X664921Y7874D03*
X672795Y8268D03*
X657047Y30315D03*
X664921Y29922D03*
X672795Y30315D03*
X657047Y24803D03*
X664921Y24410D03*
X672795Y24803D03*
X657047Y19292D03*
X664921Y18898D03*
X672795Y19292D03*
X657047Y13780D03*
X664921Y13386D03*
X672795Y13780D03*
X657047Y52362D03*
X664921Y51969D03*
X672795Y52362D03*
X657047Y46851D03*
X664921Y46457D03*
X672795Y46851D03*
X657047Y41339D03*
X664921Y40945D03*
X672795Y41339D03*
X657047Y35827D03*
X664921Y35433D03*
X672795Y35827D03*
X680669Y7874D03*
Y29922D03*
X688543Y30315D03*
X680669Y24410D03*
X688543Y24803D03*
X680669Y18898D03*
X688543Y19292D03*
X680669Y13386D03*
X688543Y13780D03*
X680669Y51969D03*
X688543Y52362D03*
X680669Y46457D03*
X688543Y46851D03*
X680669Y40945D03*
X688543Y41339D03*
X680669Y35433D03*
X688543Y35827D03*
X1336733Y7874D03*
X1344607Y8268D03*
X1336733Y29922D03*
X1344607Y30315D03*
X1336733Y24410D03*
X1344607Y24803D03*
X1336733Y18898D03*
X1344607Y19292D03*
X1336733Y13386D03*
X1344607Y13780D03*
X1336733Y51969D03*
X1344607Y52362D03*
X1336733Y46457D03*
X1344607Y46851D03*
X1336733Y40945D03*
X1344607Y41339D03*
X1336733Y35433D03*
X1344607Y35827D03*
X1352481Y7874D03*
X1360355Y8268D03*
X1352481Y29922D03*
X1360355Y30315D03*
X1352481Y24410D03*
X1360355Y24803D03*
X1352481Y18898D03*
X1360355Y19292D03*
X1352481Y13386D03*
X1360355Y13780D03*
X1352481Y51969D03*
X1360355Y52362D03*
X1352481Y46457D03*
X1360355Y46851D03*
X1352481Y40945D03*
X1360355Y41339D03*
X1352481Y35433D03*
X1360355Y35827D03*
X1368229Y7874D03*
Y29922D03*
X1376103Y30315D03*
X1368229Y24410D03*
X1376103Y24803D03*
X1368229Y18898D03*
X1376103Y19292D03*
X1368229Y13386D03*
X1376103Y13780D03*
X1368229Y51969D03*
X1376103Y52362D03*
X1368229Y46457D03*
X1376103Y46851D03*
X1368229Y40945D03*
X1376103Y41339D03*
X1368229Y35433D03*
X1376103Y35827D03*
X1519252Y7874D03*
X1527126Y8268D03*
X1519252Y29922D03*
X1527126Y30315D03*
X1519252Y24410D03*
X1527126Y24803D03*
X1519252Y18898D03*
X1527126Y19292D03*
X1519252Y13386D03*
X1527126Y13780D03*
X1519252Y51969D03*
X1527126Y52362D03*
X1519252Y46457D03*
X1527126Y46851D03*
X1519252Y40945D03*
X1527126Y41339D03*
X1519252Y35433D03*
X1527126Y35827D03*
X1535000Y7874D03*
X1542874Y8268D03*
X1550748Y7874D03*
X1535000Y29922D03*
X1542874Y30315D03*
X1550748Y29922D03*
X1535000Y24410D03*
X1542874Y24803D03*
X1550748Y24410D03*
X1535000Y18898D03*
X1542874Y19292D03*
X1550748Y18898D03*
X1535000Y13386D03*
X1542874Y13780D03*
X1550748Y13386D03*
X1535000Y51969D03*
X1542874Y52362D03*
X1550748Y51969D03*
X1535000Y46457D03*
X1542874Y46851D03*
X1550748Y46457D03*
X1535000Y40945D03*
X1542874Y41339D03*
X1550748Y40945D03*
X1535000Y35433D03*
X1542874Y35827D03*
X1550748Y35433D03*
X1558622Y30315D03*
Y24803D03*
Y19292D03*
Y13780D03*
Y52362D03*
Y46851D03*
Y41339D03*
Y35827D03*
G54D16*
X40827Y29528D03*
Y147638D03*
G54D44*
G01X457212Y-338900D02*
Y-343900D01*
G01X455755Y-338900D02*
X458669D01*
G01X463579Y-343900D02*
X461045D01*
Y-338900D01*
X463579D01*
G01X462565Y-341317D02*
X461045D01*
G01X466145Y-338900D02*
Y-343900D01*
X468679D01*
G01X472512Y-344067D02*
X472385Y-343983D01*
Y-343817D01*
X472512Y-343733D01*
X472639Y-343817D01*
Y-343983D01*
X472512Y-344067D01*
G01Y-341817D02*
X472385Y-341733D01*
Y-341567D01*
X472512Y-341483D01*
X472639Y-341567D01*
Y-341733D01*
X472512Y-341817D01*
G01X477295Y-345567D02*
X476662Y-344733D01*
X476345Y-343900D01*
Y-340567D01*
X476662Y-339733D01*
X477295Y-338900D01*
G01X482712D02*
X482205Y-339067D01*
X481825Y-339483D01*
X481572Y-339983D01*
X481382Y-340650D01*
X481319Y-341400D01*
X481382Y-342150D01*
X481572Y-342817D01*
X481825Y-343317D01*
X482205Y-343733D01*
X482712Y-343900D01*
X483219Y-343733D01*
X483599Y-343317D01*
X483852Y-342817D01*
X484042Y-342150D01*
X484105Y-341400D01*
X484042Y-340650D01*
X483852Y-339983D01*
X483599Y-339483D01*
X483219Y-339067D01*
X482712Y-338900D01*
G01X486419Y-342900D02*
X486799Y-343483D01*
X487305Y-343817D01*
X487875Y-343900D01*
X488382Y-343817D01*
X488889Y-343400D01*
X489205Y-342900D01*
X489269Y-342400D01*
X489142Y-341817D01*
X488699Y-341400D01*
X488255Y-341233D01*
X487685D01*
G01X488255D02*
X488635Y-340983D01*
X488952Y-340567D01*
X489079Y-340067D01*
X488952Y-339567D01*
X488635Y-339150D01*
X488065Y-338900D01*
X487495Y-338983D01*
X486925Y-339317D01*
G01X493229Y-345567D02*
X493862Y-344733D01*
X494179Y-343900D01*
Y-340567D01*
X493862Y-339733D01*
X493229Y-338900D01*
G01X496619Y-342900D02*
X496999Y-343483D01*
X497505Y-343817D01*
X498075Y-343900D01*
X498582Y-343817D01*
X499089Y-343400D01*
X499405Y-342900D01*
X499469Y-342400D01*
X499342Y-341817D01*
X498899Y-341400D01*
X498455Y-341233D01*
X497885D01*
G01X498455D02*
X498835Y-340983D01*
X499152Y-340567D01*
X499279Y-340067D01*
X499152Y-339567D01*
X498835Y-339150D01*
X498265Y-338900D01*
X497695Y-338983D01*
X497125Y-339317D01*
G01X501909Y-339733D02*
X502289Y-339233D01*
X502732Y-338983D01*
X503239Y-338900D01*
X503872Y-339067D01*
X504315Y-339483D01*
X504442Y-339983D01*
X504379Y-340483D01*
X504125Y-340900D01*
X502859Y-341733D01*
X502289Y-342317D01*
X501909Y-343150D01*
X501782Y-343900D01*
X504442D01*
G01X508085D02*
X508212Y-342817D01*
X508402Y-341900D01*
X508655Y-341067D01*
X508972Y-340150D01*
X509479Y-338900D01*
X506945D01*
G01X512489Y-342233D02*
X514135D01*
G01X517209Y-339733D02*
X517589Y-339233D01*
X518032Y-338983D01*
X518539Y-338900D01*
X519172Y-339067D01*
X519615Y-339483D01*
X519742Y-339983D01*
X519679Y-340483D01*
X519425Y-340900D01*
X518159Y-341733D01*
X517589Y-342317D01*
X517209Y-343150D01*
X517082Y-343900D01*
X519742D01*
G01X522119Y-342900D02*
X522499Y-343483D01*
X523005Y-343817D01*
X523575Y-343900D01*
X524082Y-343817D01*
X524589Y-343400D01*
X524905Y-342900D01*
X524969Y-342400D01*
X524842Y-341817D01*
X524399Y-341400D01*
X523955Y-341233D01*
X523385D01*
G01X523955D02*
X524335Y-340983D01*
X524652Y-340567D01*
X524779Y-340067D01*
X524652Y-339567D01*
X524335Y-339150D01*
X523765Y-338900D01*
X523195Y-338983D01*
X522625Y-339317D01*
G01X529372Y-343900D02*
Y-338900D01*
X527029Y-342483D01*
X530195D01*
G01X532319Y-343150D02*
X532699Y-343567D01*
X533142Y-343817D01*
X533712Y-343900D01*
X534282Y-343733D01*
X534725Y-343400D01*
X535042Y-342817D01*
X535105Y-342150D01*
X534979Y-341483D01*
X534662Y-341067D01*
X534219Y-340733D01*
X533775Y-340650D01*
X533332Y-340733D01*
X532762Y-341067D01*
X532952Y-338900D01*
X534662D01*
G01X542709Y-343900D02*
Y-338900D01*
X545115D01*
G01X544229Y-341317D02*
X542709D01*
G01X547429Y-343900D02*
X549012Y-338900D01*
X550595Y-343900D01*
G01X550025Y-342150D02*
X547999D01*
G01X552782Y-343900D02*
X555442Y-338900D01*
G01X552782D02*
X555442Y-343900D01*
G01X559212Y-344067D02*
X559085Y-343983D01*
Y-343817D01*
X559212Y-343733D01*
X559339Y-343817D01*
Y-343983D01*
X559212Y-344067D01*
G01Y-341817D02*
X559085Y-341733D01*
Y-341567D01*
X559212Y-341483D01*
X559339Y-341567D01*
Y-341733D01*
X559212Y-341817D01*
G01X563995Y-345567D02*
X563362Y-344733D01*
X563045Y-343900D01*
Y-340567D01*
X563362Y-339733D01*
X563995Y-338900D01*
G01X569412D02*
X568905Y-339067D01*
X568525Y-339483D01*
X568272Y-339983D01*
X568082Y-340650D01*
X568019Y-341400D01*
X568082Y-342150D01*
X568272Y-342817D01*
X568525Y-343317D01*
X568905Y-343733D01*
X569412Y-343900D01*
X569919Y-343733D01*
X570299Y-343317D01*
X570552Y-342817D01*
X570742Y-342150D01*
X570805Y-341400D01*
X570742Y-340650D01*
X570552Y-339983D01*
X570299Y-339483D01*
X569919Y-339067D01*
X569412Y-338900D01*
G01X573119Y-342900D02*
X573499Y-343483D01*
X574005Y-343817D01*
X574575Y-343900D01*
X575082Y-343817D01*
X575589Y-343400D01*
X575905Y-342900D01*
X575969Y-342400D01*
X575842Y-341817D01*
X575399Y-341400D01*
X574955Y-341233D01*
X574385D01*
G01X574955D02*
X575335Y-340983D01*
X575652Y-340567D01*
X575779Y-340067D01*
X575652Y-339567D01*
X575335Y-339150D01*
X574765Y-338900D01*
X574195Y-338983D01*
X573625Y-339317D01*
G01X579929Y-345567D02*
X580562Y-344733D01*
X580879Y-343900D01*
Y-340567D01*
X580562Y-339733D01*
X579929Y-338900D01*
G01X583319Y-342900D02*
X583699Y-343483D01*
X584205Y-343817D01*
X584775Y-343900D01*
X585282Y-343817D01*
X585789Y-343400D01*
X586105Y-342900D01*
X586169Y-342400D01*
X586042Y-341817D01*
X585599Y-341400D01*
X585155Y-341233D01*
X584585D01*
G01X585155D02*
X585535Y-340983D01*
X585852Y-340567D01*
X585979Y-340067D01*
X585852Y-339567D01*
X585535Y-339150D01*
X584965Y-338900D01*
X584395Y-338983D01*
X583825Y-339317D01*
G01X588735Y-343317D02*
X589179Y-343733D01*
X589685Y-343900D01*
X590192Y-343733D01*
X590635Y-343233D01*
X590952Y-342483D01*
X591079Y-341733D01*
Y-340817D01*
X590952Y-340067D01*
X590635Y-339400D01*
X590255Y-339067D01*
X589812Y-338900D01*
X589305Y-339067D01*
X588925Y-339400D01*
X588672Y-339900D01*
X588545Y-340567D01*
X588672Y-341150D01*
X588989Y-341733D01*
X589369Y-342067D01*
X589812Y-342150D01*
X590319Y-341983D01*
X590699Y-341567D01*
X591079Y-340817D01*
G01X594785Y-343900D02*
X594912Y-342817D01*
X595102Y-341900D01*
X595355Y-341067D01*
X595672Y-340150D01*
X596179Y-338900D01*
X593645D01*
G01X599189Y-342233D02*
X600835D01*
G01X603719Y-342900D02*
X604099Y-343483D01*
X604605Y-343817D01*
X605175Y-343900D01*
X605682Y-343817D01*
X606189Y-343400D01*
X606505Y-342900D01*
X606569Y-342400D01*
X606442Y-341817D01*
X605999Y-341400D01*
X605555Y-341233D01*
X604985D01*
G01X605555D02*
X605935Y-340983D01*
X606252Y-340567D01*
X606379Y-340067D01*
X606252Y-339567D01*
X605935Y-339150D01*
X605365Y-338900D01*
X604795Y-338983D01*
X604225Y-339317D01*
G01X609009Y-341817D02*
X609452Y-341233D01*
X609832Y-340900D01*
X610339Y-340733D01*
X610782Y-340900D01*
X611099Y-341233D01*
X611352Y-341733D01*
X611415Y-342317D01*
X611352Y-342817D01*
X611099Y-343317D01*
X610719Y-343733D01*
X610275Y-343900D01*
X609769Y-343733D01*
X609325Y-343233D01*
X609072Y-342483D01*
X609009Y-341650D01*
X609135Y-340567D01*
X609325Y-339983D01*
X609642Y-339400D01*
X610085Y-338983D01*
X610529Y-338900D01*
X610972Y-339067D01*
X611289Y-339483D01*
G01X615312Y-343900D02*
Y-338900D01*
X614552Y-339900D01*
G01Y-343900D02*
X616072D01*
G01X621172D02*
Y-338900D01*
X618829Y-342483D01*
X621995D01*
G01X445212Y-273900D02*
Y-348900D01*
X945212D01*
Y-273900D01*
X445212D01*
G01X640212D02*
Y-348900D01*
G01Y-323900D02*
X743212D01*
Y-298900D01*
G01X640212D02*
X743212D01*
G01Y-273900D02*
Y-348900D01*
G01X745212Y-273900D02*
Y-348900D01*
G01X750719Y-333900D02*
Y-328900D01*
X751985D01*
X752492Y-329150D01*
X752872Y-329483D01*
X753189Y-329983D01*
X753442Y-330567D01*
X753505Y-331400D01*
X753442Y-332233D01*
X753189Y-332817D01*
X752872Y-333317D01*
X752492Y-333650D01*
X751985Y-333900D01*
X750719D01*
G01X755629D02*
X757212Y-328900D01*
X758795Y-333900D01*
G01X758225Y-332150D02*
X756199D01*
G01X762312Y-328900D02*
Y-333900D01*
G01X760855Y-328900D02*
X763769D01*
G01X768679Y-333900D02*
X766145D01*
Y-328900D01*
X768679D01*
G01X767665Y-331317D02*
X766145D01*
G01X772512Y-334067D02*
X772385Y-333983D01*
Y-333817D01*
X772512Y-333733D01*
X772639Y-333817D01*
Y-333983D01*
X772512Y-334067D01*
G01Y-331817D02*
X772385Y-331733D01*
Y-331567D01*
X772512Y-331483D01*
X772639Y-331567D01*
Y-331733D01*
X772512Y-331817D01*
G01X745212Y-323900D02*
X945212D01*
G01X750845Y-308900D02*
Y-303900D01*
X752365D01*
X752872Y-304150D01*
X753252Y-304733D01*
X753379Y-305400D01*
X753252Y-306067D01*
X752935Y-306567D01*
X752365Y-306817D01*
X750845D01*
G01X756072Y-309067D02*
X758352Y-303900D01*
G01X760855Y-308900D02*
Y-303900D01*
X763769Y-308900D01*
Y-303900D01*
G01X767412Y-309067D02*
X767285Y-308983D01*
Y-308817D01*
X767412Y-308733D01*
X767539Y-308817D01*
Y-308983D01*
X767412Y-309067D01*
G01Y-306817D02*
X767285Y-306733D01*
Y-306567D01*
X767412Y-306483D01*
X767539Y-306567D01*
Y-306733D01*
X767412Y-306817D01*
G01X745212Y-298900D02*
X945212D01*
G01X750845Y-283900D02*
Y-278900D01*
X752365D01*
X752872Y-279150D01*
X753252Y-279733D01*
X753379Y-280400D01*
X753252Y-281067D01*
X752935Y-281567D01*
X752365Y-281817D01*
X750845D01*
G01X755945Y-283900D02*
Y-278900D01*
X757529D01*
X758035Y-279150D01*
X758352Y-279483D01*
X758479Y-280150D01*
X758352Y-280817D01*
X757972Y-281233D01*
X757529Y-281483D01*
X755945D01*
G01X757529D02*
X758479Y-283900D01*
G01X762312D02*
X761805Y-283817D01*
X761362Y-283483D01*
X760982Y-282983D01*
X760729Y-282400D01*
X760602Y-281733D01*
Y-281067D01*
X760729Y-280400D01*
X760982Y-279817D01*
X761362Y-279317D01*
X761805Y-278983D01*
X762312Y-278900D01*
X762819Y-278983D01*
X763262Y-279317D01*
X763642Y-279817D01*
X763895Y-280400D01*
X764022Y-281067D01*
Y-281733D01*
X763895Y-282400D01*
X763642Y-282983D01*
X763262Y-283483D01*
X762819Y-283817D01*
X762312Y-283900D01*
G01X766145Y-282900D02*
X766462Y-283400D01*
X766842Y-283733D01*
X767285Y-283900D01*
X767792Y-283733D01*
X768172Y-283400D01*
X768552Y-282900D01*
X768679Y-282233D01*
Y-278900D01*
G01X773779Y-283900D02*
X771245D01*
Y-278900D01*
X773779D01*
G01X772765Y-281317D02*
X771245D01*
G01X779005Y-279317D02*
X778625Y-279067D01*
X778182Y-278900D01*
X777675D01*
X777105Y-279150D01*
X776662Y-279567D01*
X776345Y-280067D01*
X776092Y-280900D01*
X776029Y-281650D01*
X776155Y-282400D01*
X776345Y-282900D01*
X776725Y-283400D01*
X777169Y-283733D01*
X777612Y-283900D01*
X778055D01*
X778499Y-283733D01*
X778879Y-283483D01*
X779195Y-283150D01*
G01X782712Y-278900D02*
Y-283900D01*
G01X781255Y-278900D02*
X784169D01*
G01X787812Y-284067D02*
X787685Y-283983D01*
Y-283817D01*
X787812Y-283733D01*
X787939Y-283817D01*
Y-283983D01*
X787812Y-284067D01*
G01Y-281817D02*
X787685Y-281733D01*
Y-281567D01*
X787812Y-281483D01*
X787939Y-281567D01*
Y-281733D01*
X787812Y-281817D01*
G01X860212Y-323900D02*
Y-348900D01*
G01X865845Y-333900D02*
Y-328900D01*
X867429D01*
X867935Y-329150D01*
X868252Y-329483D01*
X868379Y-330150D01*
X868252Y-330817D01*
X867872Y-331233D01*
X867429Y-331483D01*
X865845D01*
G01X867429D02*
X868379Y-333900D01*
G01X873479D02*
X870945D01*
Y-328900D01*
X873479D01*
G01X872465Y-331317D02*
X870945D01*
G01X875729Y-328900D02*
X877312Y-333900D01*
X878895Y-328900D01*
G01X882412Y-334067D02*
X882285Y-333983D01*
Y-333817D01*
X882412Y-333733D01*
X882539Y-333817D01*
Y-333983D01*
X882412Y-334067D01*
G01Y-331817D02*
X882285Y-331733D01*
Y-331567D01*
X882412Y-331483D01*
X882539Y-331567D01*
Y-331733D01*
X882412Y-331817D01*
G01X909212Y-323900D02*
Y-348900D01*
G01X-471400Y-391900D02*
Y1528800D01*
X2244200D01*
Y-391900D01*
X-471400D01*
G01X455917Y-335560D02*
X456544Y-336085D01*
X457249Y-336400D01*
X457875D01*
X458502Y-336085D01*
X458972Y-335560D01*
X459207Y-334825D01*
X459050Y-334090D01*
X458659Y-333460D01*
X457954Y-333040D01*
X457014Y-332830D01*
X456465Y-332410D01*
X456230Y-331675D01*
X456387Y-330940D01*
X456779Y-330415D01*
X457327Y-330100D01*
X457875D01*
X458424Y-330310D01*
X458894Y-330835D01*
G01X462217Y-336400D02*
Y-330100D01*
G01X465507D02*
Y-336400D01*
G01Y-333250D02*
X462217D01*
G01X469222Y-330100D02*
X471102D01*
G01X470162D02*
Y-336400D01*
G01X469222D02*
X471102D01*
G01X478029D02*
X474895D01*
Y-330100D01*
X478029D01*
G01X476775Y-333145D02*
X474895D01*
G01X480960Y-336400D02*
Y-330100D01*
X484564Y-336400D01*
Y-330100D01*
G01X488905Y-337555D02*
X489219Y-336190D01*
G01X495362Y-330100D02*
Y-336400D01*
G01X493560Y-330100D02*
X497164D01*
G01X499704Y-336400D02*
X501662Y-330100D01*
X503620Y-336400D01*
G01X502915Y-334195D02*
X500409D01*
G01X507022Y-330100D02*
X508902D01*
G01X507962D02*
Y-336400D01*
G01X507022D02*
X508902D01*
G01X511912Y-330100D02*
X513009Y-336400D01*
X514262Y-330100D01*
X515515Y-336400D01*
X516612Y-330100D01*
G01X518604Y-336400D02*
X520562Y-330100D01*
X522520Y-336400D01*
G01X521815Y-334195D02*
X519309D01*
G01X525060Y-336400D02*
Y-330100D01*
X528664Y-336400D01*
Y-330100D01*
G01X537895Y-336400D02*
Y-330100D01*
X539854D01*
X540480Y-330415D01*
X540872Y-330835D01*
X541029Y-331675D01*
X540872Y-332515D01*
X540402Y-333040D01*
X539854Y-333355D01*
X537895D01*
G01X539854D02*
X541029Y-336400D01*
G01X545762Y-336610D02*
X545605Y-336505D01*
Y-336295D01*
X545762Y-336190D01*
X545919Y-336295D01*
Y-336505D01*
X545762Y-336610D01*
G01X552062Y-336400D02*
X551435Y-336295D01*
X550887Y-335875D01*
X550417Y-335245D01*
X550104Y-334510D01*
X549947Y-333670D01*
Y-332830D01*
X550104Y-331990D01*
X550417Y-331255D01*
X550887Y-330625D01*
X551435Y-330205D01*
X552062Y-330100D01*
X552689Y-330205D01*
X553237Y-330625D01*
X553707Y-331255D01*
X554020Y-331990D01*
X554177Y-332830D01*
Y-333670D01*
X554020Y-334510D01*
X553707Y-335245D01*
X553237Y-335875D01*
X552689Y-336295D01*
X552062Y-336400D01*
G01X558362Y-336610D02*
X558205Y-336505D01*
Y-336295D01*
X558362Y-336190D01*
X558519Y-336295D01*
Y-336505D01*
X558362Y-336610D01*
G01X566385Y-330625D02*
X565915Y-330310D01*
X565367Y-330100D01*
X564740D01*
X564035Y-330415D01*
X563487Y-330940D01*
X563095Y-331570D01*
X562782Y-332620D01*
X562704Y-333565D01*
X562860Y-334510D01*
X563095Y-335140D01*
X563565Y-335770D01*
X564114Y-336190D01*
X564662Y-336400D01*
X565210D01*
X565759Y-336190D01*
X566229Y-335875D01*
X566620Y-335455D01*
G01X570962Y-336610D02*
X570805Y-336505D01*
Y-336295D01*
X570962Y-336190D01*
X571119Y-336295D01*
Y-336505D01*
X570962Y-336610D01*
G01X455839Y-326400D02*
Y-320100D01*
G01X458815D02*
X455839Y-323985D01*
G01X459285Y-326400D02*
X457170Y-322200D01*
G01X462139Y-320100D02*
Y-324615D01*
X462452Y-325560D01*
X463079Y-326190D01*
X463862Y-326400D01*
X464645Y-326190D01*
X465272Y-325560D01*
X465585Y-324615D01*
Y-320100D01*
G01X471729Y-326400D02*
X468595D01*
Y-320100D01*
X471729D01*
G01X470475Y-323145D02*
X468595D01*
G01X475522Y-320100D02*
X477402D01*
G01X476462D02*
Y-326400D01*
G01X475522D02*
X477402D01*
G01X487417Y-325560D02*
X488044Y-326085D01*
X488749Y-326400D01*
X489375D01*
X490002Y-326085D01*
X490472Y-325560D01*
X490707Y-324825D01*
X490550Y-324090D01*
X490159Y-323460D01*
X489454Y-323040D01*
X488514Y-322830D01*
X487965Y-322410D01*
X487730Y-321675D01*
X487887Y-320940D01*
X488279Y-320415D01*
X488827Y-320100D01*
X489375D01*
X489924Y-320310D01*
X490394Y-320835D01*
G01X493717Y-326400D02*
Y-320100D01*
G01X497007D02*
Y-326400D01*
G01Y-323250D02*
X493717D01*
G01X499704Y-326400D02*
X501662Y-320100D01*
X503620Y-326400D01*
G01X502915Y-324195D02*
X500409D01*
G01X506160Y-326400D02*
Y-320100D01*
X509764Y-326400D01*
Y-320100D01*
G01X518917Y-326400D02*
Y-320100D01*
G01X522207D02*
Y-326400D01*
G01Y-323250D02*
X518917D01*
G01X525217Y-325560D02*
X525844Y-326085D01*
X526549Y-326400D01*
X527175D01*
X527802Y-326085D01*
X528272Y-325560D01*
X528507Y-324825D01*
X528350Y-324090D01*
X527959Y-323460D01*
X527254Y-323040D01*
X526314Y-322830D01*
X525765Y-322410D01*
X525530Y-321675D01*
X525687Y-320940D01*
X526079Y-320415D01*
X526627Y-320100D01*
X527175D01*
X527724Y-320310D01*
X528194Y-320835D01*
G01X532222Y-320100D02*
X534102D01*
G01X533162D02*
Y-326400D01*
G01X532222D02*
X534102D01*
G01X537504D02*
X539462Y-320100D01*
X541420Y-326400D01*
G01X540715Y-324195D02*
X538209D01*
G01X543960Y-326400D02*
Y-320100D01*
X547564Y-326400D01*
Y-320100D01*
G01X552532Y-323250D02*
X554099D01*
Y-325140D01*
X553629Y-325770D01*
X553080Y-326190D01*
X552297Y-326400D01*
X551514Y-326190D01*
X550965Y-325770D01*
X550495Y-325140D01*
X550182Y-324405D01*
X550025Y-323565D01*
Y-322830D01*
X550182Y-322200D01*
X550495Y-321465D01*
X550965Y-320835D01*
X551435Y-320415D01*
X552062Y-320100D01*
X552610D01*
X553237Y-320310D01*
X553707Y-320730D01*
G01X558205Y-327555D02*
X558519Y-326190D01*
G01X564662Y-320100D02*
Y-326400D01*
G01X562860Y-320100D02*
X566464D01*
G01X569004Y-326400D02*
X570962Y-320100D01*
X572920Y-326400D01*
G01X572215Y-324195D02*
X569709D01*
G01X577262Y-326400D02*
X576635Y-326295D01*
X576087Y-325875D01*
X575617Y-325245D01*
X575304Y-324510D01*
X575147Y-323670D01*
Y-322830D01*
X575304Y-321990D01*
X575617Y-321255D01*
X576087Y-320625D01*
X576635Y-320205D01*
X577262Y-320100D01*
X577889Y-320205D01*
X578437Y-320625D01*
X578907Y-321255D01*
X579220Y-321990D01*
X579377Y-322830D01*
Y-323670D01*
X579220Y-324510D01*
X578907Y-325245D01*
X578437Y-325875D01*
X577889Y-326295D01*
X577262Y-326400D01*
G01X589862D02*
Y-323565D01*
X588295Y-320100D01*
G01X591429D02*
X589862Y-323565D01*
G01X594439Y-320100D02*
Y-324615D01*
X594752Y-325560D01*
X595379Y-326190D01*
X596162Y-326400D01*
X596945Y-326190D01*
X597572Y-325560D01*
X597885Y-324615D01*
Y-320100D01*
G01X600504Y-326400D02*
X602462Y-320100D01*
X604420Y-326400D01*
G01X603715Y-324195D02*
X601209D01*
G01X606960Y-326400D02*
Y-320100D01*
X610564Y-326400D01*
Y-320100D01*
G01X455760Y-316400D02*
Y-310100D01*
X459364Y-316400D01*
Y-310100D01*
G01X463862Y-316400D02*
X463235Y-316295D01*
X462687Y-315875D01*
X462217Y-315245D01*
X461904Y-314510D01*
X461747Y-313670D01*
Y-312830D01*
X461904Y-311990D01*
X462217Y-311255D01*
X462687Y-310625D01*
X463235Y-310205D01*
X463862Y-310100D01*
X464489Y-310205D01*
X465037Y-310625D01*
X465507Y-311255D01*
X465820Y-311990D01*
X465977Y-312830D01*
Y-313670D01*
X465820Y-314510D01*
X465507Y-315245D01*
X465037Y-315875D01*
X464489Y-316295D01*
X463862Y-316400D01*
G01X470162Y-316610D02*
X470005Y-316505D01*
Y-316295D01*
X470162Y-316190D01*
X470319Y-316295D01*
Y-316505D01*
X470162Y-316610D01*
G01X476462Y-316400D02*
Y-310100D01*
X475522Y-311360D01*
G01Y-316400D02*
X477402D01*
G01X482762D02*
X483310Y-316295D01*
X483937Y-315980D01*
X484329Y-315455D01*
X484485Y-314720D01*
X484329Y-313985D01*
X483859Y-313355D01*
X483154Y-313040D01*
X482370D01*
X481900Y-312830D01*
X481509Y-312305D01*
X481352Y-311570D01*
X481587Y-310835D01*
X482135Y-310310D01*
X482762Y-310100D01*
X483389Y-310310D01*
X483937Y-310835D01*
X484172Y-311570D01*
X484015Y-312305D01*
X483624Y-312830D01*
X483154Y-313040D01*
X482370D01*
X481665Y-313355D01*
X481195Y-313985D01*
X481039Y-314720D01*
X481195Y-315455D01*
X481587Y-315980D01*
X482214Y-316295D01*
X482762Y-316400D01*
G01X489062D02*
X489610Y-316295D01*
X490237Y-315980D01*
X490629Y-315455D01*
X490785Y-314720D01*
X490629Y-313985D01*
X490159Y-313355D01*
X489454Y-313040D01*
X488670D01*
X488200Y-312830D01*
X487809Y-312305D01*
X487652Y-311570D01*
X487887Y-310835D01*
X488435Y-310310D01*
X489062Y-310100D01*
X489689Y-310310D01*
X490237Y-310835D01*
X490472Y-311570D01*
X490315Y-312305D01*
X489924Y-312830D01*
X489454Y-313040D01*
X488670D01*
X487965Y-313355D01*
X487495Y-313985D01*
X487339Y-314720D01*
X487495Y-315455D01*
X487887Y-315980D01*
X488514Y-316295D01*
X489062Y-316400D01*
G01X495205Y-317555D02*
X495519Y-316190D01*
G01X499312Y-310100D02*
X500409Y-316400D01*
X501662Y-310100D01*
X502915Y-316400D01*
X504012Y-310100D01*
G01X509529Y-316400D02*
X506395D01*
Y-310100D01*
X509529D01*
G01X508275Y-313145D02*
X506395D01*
G01X512460Y-316400D02*
Y-310100D01*
X516064Y-316400D01*
Y-310100D01*
G01X525217Y-316400D02*
Y-310100D01*
G01X528507D02*
Y-316400D01*
G01Y-313250D02*
X525217D01*
G01X530812Y-310100D02*
X531909Y-316400D01*
X533162Y-310100D01*
X534415Y-316400D01*
X535512Y-310100D01*
G01X537504Y-316400D02*
X539462Y-310100D01*
X541420Y-316400D01*
G01X540715Y-314195D02*
X538209D01*
G01X550574Y-311150D02*
X551044Y-310520D01*
X551592Y-310205D01*
X552219Y-310100D01*
X553002Y-310310D01*
X553550Y-310835D01*
X553707Y-311465D01*
X553629Y-312095D01*
X553315Y-312620D01*
X551749Y-313670D01*
X551044Y-314405D01*
X550574Y-315455D01*
X550417Y-316400D01*
X553707D01*
G01X556560D02*
Y-310100D01*
X560164Y-316400D01*
Y-310100D01*
G01X562939Y-316400D02*
Y-310100D01*
X564505D01*
X565132Y-310415D01*
X565602Y-310835D01*
X565994Y-311465D01*
X566307Y-312200D01*
X566385Y-313250D01*
X566307Y-314300D01*
X565994Y-315035D01*
X565602Y-315665D01*
X565132Y-316085D01*
X564505Y-316400D01*
X562939D01*
G01X575695D02*
Y-310100D01*
X577654D01*
X578280Y-310415D01*
X578672Y-310835D01*
X578829Y-311675D01*
X578672Y-312515D01*
X578202Y-313040D01*
X577654Y-313355D01*
X575695D01*
G01X577654D02*
X578829Y-316400D01*
G01X581839D02*
Y-310100D01*
X583405D01*
X584032Y-310415D01*
X584502Y-310835D01*
X584894Y-311465D01*
X585207Y-312200D01*
X585285Y-313250D01*
X585207Y-314300D01*
X584894Y-315035D01*
X584502Y-315665D01*
X584032Y-316085D01*
X583405Y-316400D01*
X581839D01*
G01X589862Y-316610D02*
X589705Y-316505D01*
Y-316295D01*
X589862Y-316190D01*
X590019Y-316295D01*
Y-316505D01*
X589862Y-316610D01*
G01X479862Y-303700D02*
X477342Y-303283D01*
X475137Y-301617D01*
X473247Y-299117D01*
X471987Y-296200D01*
X471357Y-292867D01*
Y-289533D01*
X471987Y-286200D01*
X473247Y-283283D01*
X475137Y-280784D01*
X477342Y-279117D01*
X479862Y-278700D01*
X482382Y-279117D01*
X484587Y-280784D01*
X486477Y-283283D01*
X487737Y-286200D01*
X488367Y-289533D01*
Y-292867D01*
X487737Y-296200D01*
X486477Y-299117D01*
X484587Y-301617D01*
X482382Y-303283D01*
X479862Y-303700D01*
G01X482382Y-297033D02*
X486162Y-303700D01*
G01X499707Y-287034D02*
Y-298700D01*
X500967Y-301617D01*
X502857Y-303283D01*
X505062Y-303700D01*
X507267Y-303283D01*
X509157Y-301617D01*
X510417Y-298700D01*
G01Y-303700D02*
Y-287034D01*
G01X535932Y-303700D02*
Y-287034D01*
G01Y-289950D02*
X534672Y-288284D01*
X532782Y-287450D01*
X530577Y-287034D01*
X528372Y-287867D01*
X526482Y-289533D01*
X525222Y-292034D01*
X524592Y-295367D01*
X525222Y-298700D01*
X526482Y-301201D01*
X528372Y-302867D01*
X530577Y-303700D01*
X532782Y-303283D01*
X534672Y-302034D01*
X535932Y-300367D01*
G01X550107Y-303700D02*
Y-287034D01*
G01Y-291200D02*
X551367Y-289117D01*
X553257Y-287450D01*
X555777Y-287034D01*
X557982Y-287450D01*
X559872Y-289117D01*
X560817Y-292034D01*
Y-303700D01*
G01X580662Y-278700D02*
Y-303700D01*
G01X576252Y-287034D02*
X585072D01*
G01X611532Y-303700D02*
Y-287034D01*
G01Y-289950D02*
X610272Y-288284D01*
X608382Y-287450D01*
X606177Y-287034D01*
X603972Y-287867D01*
X602082Y-289533D01*
X600822Y-292034D01*
X600192Y-295367D01*
X600822Y-298700D01*
X602082Y-301201D01*
X603972Y-302867D01*
X606177Y-303700D01*
X608382Y-303283D01*
X610272Y-302034D01*
X611532Y-300367D01*
G01X651212Y-283400D02*
Y-291400D01*
X655212D01*
G01X663012D02*
Y-286067D01*
G01Y-287000D02*
X662612Y-286467D01*
X662012Y-286200D01*
X661312Y-286067D01*
X660612Y-286333D01*
X660012Y-286867D01*
X659612Y-287667D01*
X659412Y-288733D01*
X659612Y-289800D01*
X660012Y-290600D01*
X660612Y-291133D01*
X661312Y-291400D01*
X662012Y-291267D01*
X662612Y-290867D01*
X663012Y-290334D01*
G01X667112Y-293800D02*
X667712Y-294067D01*
X668512Y-293800D01*
X669012Y-293267D01*
X669412Y-292600D01*
X670012Y-290467D01*
X671312Y-286067D01*
G01X668112D02*
X670012Y-290467D01*
G01X675712Y-287800D02*
X678912D01*
X678612Y-286867D01*
X678112Y-286333D01*
X677412Y-286067D01*
X676712Y-286200D01*
X676112Y-286600D01*
X675712Y-287533D01*
X675512Y-288334D01*
Y-289133D01*
X675712Y-289933D01*
X676212Y-290733D01*
X676812Y-291267D01*
X677512Y-291400D01*
X678212Y-291133D01*
X678912Y-290334D01*
G01X683812Y-291400D02*
Y-286067D01*
G01Y-287133D02*
X684312Y-286600D01*
X684812Y-286200D01*
X685512Y-286067D01*
X686012Y-286200D01*
X686612Y-286600D01*
G01X673512Y-333400D02*
X675912D01*
G01X674712D02*
Y-341400D01*
G01X673512D02*
X675912D01*
G01X681312D02*
Y-336067D01*
G01Y-337133D02*
X681812Y-336600D01*
X682312Y-336200D01*
X683012Y-336067D01*
X683512Y-336200D01*
X684112Y-336600D01*
G01X689212Y-337800D02*
X692412D01*
X692112Y-336867D01*
X691612Y-336333D01*
X690912Y-336067D01*
X690212Y-336200D01*
X689612Y-336600D01*
X689212Y-337533D01*
X689012Y-338334D01*
Y-339133D01*
X689212Y-339933D01*
X689712Y-340733D01*
X690312Y-341267D01*
X691012Y-341400D01*
X691712Y-341133D01*
X692412Y-340334D01*
G01X697012Y-341400D02*
Y-336067D01*
G01Y-337400D02*
X697412Y-336733D01*
X698012Y-336200D01*
X698812Y-336067D01*
X699512Y-336200D01*
X700112Y-336733D01*
X700412Y-337667D01*
Y-341400D01*
G01X705212Y-337800D02*
X708412D01*
X708112Y-336867D01*
X707612Y-336333D01*
X706912Y-336067D01*
X706212Y-336200D01*
X705612Y-336600D01*
X705212Y-337533D01*
X705012Y-338334D01*
Y-339133D01*
X705212Y-339933D01*
X705712Y-340733D01*
X706312Y-341267D01*
X707012Y-341400D01*
X707712Y-341133D01*
X708412Y-340334D01*
G01X675512Y-312133D02*
X675912Y-311733D01*
X676212Y-311067D01*
X676412Y-310133D01*
X676212Y-309333D01*
X675812Y-308800D01*
X675112Y-308400D01*
X672412D01*
Y-316400D01*
X675712D01*
X676412Y-315867D01*
X676812Y-315067D01*
X677012Y-314133D01*
X676812Y-313200D01*
X676212Y-312400D01*
X675512Y-312133D01*
X672412D01*
G01X682712Y-316400D02*
X681912Y-316267D01*
X681212Y-315733D01*
X680612Y-314933D01*
X680212Y-314000D01*
X680012Y-312933D01*
Y-311867D01*
X680212Y-310800D01*
X680612Y-309867D01*
X681212Y-309067D01*
X681912Y-308533D01*
X682712Y-308400D01*
X683512Y-308533D01*
X684212Y-309067D01*
X684812Y-309867D01*
X685212Y-310800D01*
X685412Y-311867D01*
Y-312933D01*
X685212Y-314000D01*
X684812Y-314933D01*
X684212Y-315733D01*
X683512Y-316267D01*
X682712Y-316400D01*
G01X690712Y-308400D02*
Y-316400D01*
G01X688412Y-308400D02*
X693012D01*
G01X698712D02*
Y-316400D01*
G01X696412Y-308400D02*
X701012D01*
G01X706712Y-316400D02*
X705912Y-316267D01*
X705212Y-315733D01*
X704612Y-314933D01*
X704212Y-314000D01*
X704012Y-312933D01*
Y-311867D01*
X704212Y-310800D01*
X704612Y-309867D01*
X705212Y-309067D01*
X705912Y-308533D01*
X706712Y-308400D01*
X707512Y-308533D01*
X708212Y-309067D01*
X708812Y-309867D01*
X709212Y-310800D01*
X709412Y-311867D01*
Y-312933D01*
X709212Y-314000D01*
X708812Y-314933D01*
X708212Y-315733D01*
X707512Y-316267D01*
X706712Y-316400D01*
G01X712112D02*
Y-308400D01*
X714712Y-315067D01*
X717312Y-308400D01*
Y-316400D01*
G01X704712Y-291400D02*
X705412Y-291267D01*
X706212Y-290867D01*
X706712Y-290200D01*
X706912Y-289267D01*
X706712Y-288334D01*
X706112Y-287533D01*
X705212Y-287133D01*
X704212D01*
X703612Y-286867D01*
X703112Y-286200D01*
X702912Y-285267D01*
X703212Y-284333D01*
X703912Y-283667D01*
X704712Y-283400D01*
X705512Y-283667D01*
X706212Y-284333D01*
X706512Y-285267D01*
X706312Y-286200D01*
X705812Y-286867D01*
X705212Y-287133D01*
X704212D01*
X703312Y-287533D01*
X702712Y-288334D01*
X702512Y-289267D01*
X702712Y-290200D01*
X703212Y-290867D01*
X704012Y-291267D01*
X704712Y-291400D01*
G01X777812Y-334733D02*
X778412Y-333933D01*
X779112Y-333533D01*
X779912Y-333400D01*
X780912Y-333667D01*
X781612Y-334333D01*
X781812Y-335133D01*
X781712Y-335934D01*
X781312Y-336600D01*
X779312Y-337933D01*
X778412Y-338867D01*
X777812Y-340200D01*
X777612Y-341400D01*
X781812D01*
G01X787712Y-333400D02*
X786912Y-333667D01*
X786312Y-334333D01*
X785912Y-335133D01*
X785612Y-336200D01*
X785512Y-337400D01*
X785612Y-338600D01*
X785912Y-339667D01*
X786312Y-340467D01*
X786912Y-341133D01*
X787712Y-341400D01*
X788512Y-341133D01*
X789112Y-340467D01*
X789512Y-339667D01*
X789812Y-338600D01*
X789912Y-337400D01*
X789812Y-336200D01*
X789512Y-335133D01*
X789112Y-334333D01*
X788512Y-333667D01*
X787712Y-333400D01*
G01X795712Y-341400D02*
Y-333400D01*
X794512Y-335000D01*
G01Y-341400D02*
X796912D01*
G01X801812Y-334733D02*
X802412Y-333933D01*
X803112Y-333533D01*
X803912Y-333400D01*
X804912Y-333667D01*
X805612Y-334333D01*
X805812Y-335133D01*
X805712Y-335934D01*
X805312Y-336600D01*
X803312Y-337933D01*
X802412Y-338867D01*
X801812Y-340200D01*
X801612Y-341400D01*
X805812D01*
G01X809912Y-341667D02*
X813512Y-333400D01*
G01X819712Y-341400D02*
Y-333400D01*
X818512Y-335000D01*
G01Y-341400D02*
X820912D01*
G01X827712Y-333400D02*
X826912Y-333667D01*
X826312Y-334333D01*
X825912Y-335133D01*
X825612Y-336200D01*
X825512Y-337400D01*
X825612Y-338600D01*
X825912Y-339667D01*
X826312Y-340467D01*
X826912Y-341133D01*
X827712Y-341400D01*
X828512Y-341133D01*
X829112Y-340467D01*
X829512Y-339667D01*
X829812Y-338600D01*
X829912Y-337400D01*
X829812Y-336200D01*
X829512Y-335133D01*
X829112Y-334333D01*
X828512Y-333667D01*
X827712Y-333400D01*
G01X833912Y-341667D02*
X837512Y-333400D01*
G01X841512Y-339800D02*
X842112Y-340733D01*
X842912Y-341267D01*
X843812Y-341400D01*
X844612Y-341267D01*
X845412Y-340600D01*
X845912Y-339800D01*
X846012Y-339000D01*
X845812Y-338067D01*
X845112Y-337400D01*
X844412Y-337133D01*
X843512D01*
G01X844412D02*
X845012Y-336733D01*
X845512Y-336067D01*
X845712Y-335267D01*
X845512Y-334467D01*
X845012Y-333800D01*
X844112Y-333400D01*
X843212Y-333533D01*
X842312Y-334067D01*
G01X851712Y-341400D02*
Y-333400D01*
X850512Y-335000D01*
G01Y-341400D02*
X852912D01*
G01X777512Y-316400D02*
Y-308400D01*
X779512D01*
X780312Y-308800D01*
X780912Y-309333D01*
X781412Y-310133D01*
X781812Y-311067D01*
X781912Y-312400D01*
X781812Y-313733D01*
X781412Y-314667D01*
X780912Y-315467D01*
X780312Y-316000D01*
X779512Y-316400D01*
X777512D01*
G01X785212D02*
X787712Y-308400D01*
X790212Y-316400D01*
G01X789312Y-313600D02*
X786112D01*
G01X795712Y-308400D02*
X794912Y-308667D01*
X794312Y-309333D01*
X793912Y-310133D01*
X793612Y-311200D01*
X793512Y-312400D01*
X793612Y-313600D01*
X793912Y-314667D01*
X794312Y-315467D01*
X794912Y-316133D01*
X795712Y-316400D01*
X796512Y-316133D01*
X797112Y-315467D01*
X797512Y-314667D01*
X797812Y-313600D01*
X797912Y-312400D01*
X797812Y-311200D01*
X797512Y-310133D01*
X797112Y-309333D01*
X796512Y-308667D01*
X795712Y-308400D01*
G01X803712D02*
Y-316400D01*
G01X801412Y-308400D02*
X806012D01*
G01X809812Y-313067D02*
X810512Y-312133D01*
X811112Y-311600D01*
X811912Y-311333D01*
X812612Y-311600D01*
X813112Y-312133D01*
X813512Y-312933D01*
X813612Y-313867D01*
X813512Y-314667D01*
X813112Y-315467D01*
X812512Y-316133D01*
X811812Y-316400D01*
X811012Y-316133D01*
X810312Y-315334D01*
X809912Y-314133D01*
X809812Y-312800D01*
X810012Y-311067D01*
X810312Y-310133D01*
X810812Y-309200D01*
X811512Y-308533D01*
X812212Y-308400D01*
X812912Y-308667D01*
X813412Y-309333D01*
G01X817112Y-316400D02*
Y-308400D01*
X819712Y-315067D01*
X822312Y-308400D01*
Y-316400D01*
G01X827712Y-308400D02*
Y-316400D01*
G01X825412Y-308400D02*
X830012D01*
G01X833612Y-316400D02*
Y-308400D01*
G01X837812D02*
Y-316400D01*
G01Y-312400D02*
X833612D01*
G01X843712Y-316400D02*
X844412Y-316267D01*
X845212Y-315867D01*
X845712Y-315200D01*
X845912Y-314267D01*
X845712Y-313334D01*
X845112Y-312533D01*
X844212Y-312133D01*
X843212D01*
X842612Y-311867D01*
X842112Y-311200D01*
X841912Y-310267D01*
X842212Y-309333D01*
X842912Y-308667D01*
X843712Y-308400D01*
X844512Y-308667D01*
X845212Y-309333D01*
X845512Y-310267D01*
X845312Y-311200D01*
X844812Y-311867D01*
X844212Y-312133D01*
X843212D01*
X842312Y-312533D01*
X841712Y-313334D01*
X841512Y-314267D01*
X841712Y-315200D01*
X842212Y-315867D01*
X843012Y-316267D01*
X843712Y-316400D01*
G01X853912Y-309067D02*
X853312Y-308667D01*
X852612Y-308400D01*
X851812D01*
X850912Y-308800D01*
X850212Y-309467D01*
X849712Y-310267D01*
X849312Y-311600D01*
X849212Y-312800D01*
X849412Y-314000D01*
X849712Y-314800D01*
X850312Y-315600D01*
X851012Y-316133D01*
X851712Y-316400D01*
X852412D01*
X853112Y-316133D01*
X853712Y-315733D01*
X854212Y-315200D01*
G01X859712Y-308400D02*
X858912Y-308667D01*
X858312Y-309333D01*
X857912Y-310133D01*
X857612Y-311200D01*
X857512Y-312400D01*
X857612Y-313600D01*
X857912Y-314667D01*
X858312Y-315467D01*
X858912Y-316133D01*
X859712Y-316400D01*
X860512Y-316133D01*
X861112Y-315467D01*
X861512Y-314667D01*
X861812Y-313600D01*
X861912Y-312400D01*
X861812Y-311200D01*
X861512Y-310133D01*
X861112Y-309333D01*
X860512Y-308667D01*
X859712Y-308400D01*
G01X799712Y-283400D02*
Y-291400D01*
G01X797412Y-283400D02*
X802012D01*
G01X805812Y-288067D02*
X806512Y-287133D01*
X807112Y-286600D01*
X807912Y-286333D01*
X808612Y-286600D01*
X809112Y-287133D01*
X809512Y-287933D01*
X809612Y-288867D01*
X809512Y-289667D01*
X809112Y-290467D01*
X808512Y-291133D01*
X807812Y-291400D01*
X807012Y-291133D01*
X806312Y-290334D01*
X805912Y-289133D01*
X805812Y-287800D01*
X806012Y-286067D01*
X806312Y-285133D01*
X806812Y-284200D01*
X807512Y-283533D01*
X808212Y-283400D01*
X808912Y-283667D01*
X809412Y-284333D01*
G01X813112Y-291400D02*
Y-283400D01*
X815712Y-290067D01*
X818312Y-283400D01*
Y-291400D01*
G01X820712Y-294067D02*
X826712D01*
G01X831712Y-283400D02*
Y-291400D01*
G01X829412Y-283400D02*
X834012D01*
G01X838312Y-291400D02*
Y-286067D01*
G01Y-287133D02*
X838812Y-286600D01*
X839312Y-286200D01*
X840012Y-286067D01*
X840512Y-286200D01*
X841112Y-286600D01*
G01X849512Y-291400D02*
Y-286067D01*
G01Y-287000D02*
X849112Y-286467D01*
X848512Y-286200D01*
X847812Y-286067D01*
X847112Y-286333D01*
X846512Y-286867D01*
X846112Y-287667D01*
X845912Y-288733D01*
X846112Y-289800D01*
X846512Y-290600D01*
X847112Y-291133D01*
X847812Y-291400D01*
X848512Y-291267D01*
X849112Y-290867D01*
X849512Y-290334D01*
G01X853612Y-293800D02*
X854212Y-294067D01*
X855012Y-293800D01*
X855512Y-293267D01*
X855912Y-292600D01*
X856512Y-290467D01*
X857812Y-286067D01*
G01X854612D02*
X856512Y-290467D01*
G01X860712Y-294067D02*
X866712D01*
G01X872512Y-287133D02*
X872912Y-286733D01*
X873212Y-286067D01*
X873412Y-285133D01*
X873212Y-284333D01*
X872812Y-283800D01*
X872112Y-283400D01*
X869412D01*
Y-291400D01*
X872712D01*
X873412Y-290867D01*
X873812Y-290067D01*
X874012Y-289133D01*
X873812Y-288200D01*
X873212Y-287400D01*
X872512Y-287133D01*
X869412D01*
G01X877712Y-291400D02*
Y-283400D01*
X880112D01*
X880912Y-283800D01*
X881512Y-284733D01*
X881712Y-285800D01*
X881512Y-286867D01*
X881012Y-287667D01*
X880112Y-288067D01*
X877712D01*
G01X896912Y-334067D02*
X896312Y-333667D01*
X895612Y-333400D01*
X894812D01*
X893912Y-333800D01*
X893212Y-334467D01*
X892712Y-335267D01*
X892312Y-336600D01*
X892212Y-337800D01*
X892412Y-339000D01*
X892712Y-339800D01*
X893312Y-340600D01*
X894012Y-341133D01*
X894712Y-341400D01*
X895412D01*
X896112Y-341133D01*
X896712Y-340733D01*
X897212Y-340200D01*
G01X922212Y-341400D02*
Y-333400D01*
X921012Y-335000D01*
G01Y-341400D02*
X923412D01*
G01X928312Y-338067D02*
X929012Y-337133D01*
X929612Y-336600D01*
X930412Y-336333D01*
X931112Y-336600D01*
X931612Y-337133D01*
X932012Y-337933D01*
X932112Y-338867D01*
X932012Y-339667D01*
X931612Y-340467D01*
X931012Y-341133D01*
X930312Y-341400D01*
X929512Y-341133D01*
X928812Y-340334D01*
X928412Y-339133D01*
X928312Y-337800D01*
X928512Y-336067D01*
X928812Y-335133D01*
X929312Y-334200D01*
X930012Y-333533D01*
X930712Y-333400D01*
X931412Y-333667D01*
X931912Y-334333D01*
G54D26*
X306772Y67913D03*
X612047D03*
X1176851D03*
X1482126D03*
G54D17*
X44528Y41339D03*
Y53150D03*
X56339Y41339D03*
Y53150D03*
X44528Y64961D03*
Y76772D03*
X56339Y64961D03*
Y76772D03*
X44528Y88583D03*
Y100394D03*
X56339Y88583D03*
Y100394D03*
X44528Y112205D03*
Y124016D03*
X56339Y112205D03*
Y124016D03*
X44528Y135827D03*
X392795Y56653D03*
X542087Y56654D03*
X655453Y132244D03*
X702697D03*
X730295D03*
X777539D03*
X1262874Y56654D03*
X1412166Y56653D03*
X1525531Y132244D03*
X1572775D03*
X1600374D03*
X1647618D03*
G54D35*
X468859Y115666D03*
Y141650D03*
X488859Y115666D03*
X478859D03*
X483859Y125666D03*
X473859D03*
X478859Y141650D03*
X488859D03*
X473859Y151650D03*
X483859D03*
X498859Y115666D03*
X503859Y125666D03*
X493859D03*
X498859Y141650D03*
X493859Y151650D03*
X1338938Y115666D03*
X1343938Y125666D03*
X1338938Y141650D03*
X1343938Y151650D03*
X1358938Y115666D03*
X1348938D03*
X1363938Y125666D03*
X1353938D03*
X1348938Y141650D03*
X1358938D03*
X1353938Y151650D03*
X1363938D03*
X1368938Y115666D03*
X1373938Y125666D03*
X1368938Y141650D03*
G54D45*
G01X666614Y121000D02*
X664804Y122810D01*
Y124068D01*
G03X664218Y125482I-1999J0D01*
G01X664187Y125513D01*
G03X662772Y126100I-1415J-1412D01*
G01X660448D01*
G03X658058Y125110I0J-3380D01*
G01X654090Y121142D01*
G03X653100Y118752I2390J-2390D01*
G01Y107108D01*
G02X652918Y106670I-618J0D01*
G01X642590Y96342D01*
G03X641600Y93952I2390J-2390D01*
G01Y19448D01*
G03X642590Y17058I3380J0D01*
G01X643206Y16442D01*
G03X645596Y15452I2390J2390D01*
G01X647107D01*
X649173Y13386D01*
G01X661614Y121000D02*
X663424Y122810D01*
Y124068D01*
G03X663242Y124506I-618J0D01*
G01X663210Y124538D01*
G03X662772Y124720I-438J-436D01*
G01X660448D01*
G03X659034Y124134I0J-1999D01*
G01X655066Y120166D01*
G03X654480Y118752I1413J-1414D01*
G01Y107108D01*
G02X653894Y105694I-1999J0D01*
G01X643566Y95366D01*
G03X642980Y93952I1413J-1414D01*
G01Y91108D01*
X643660Y90429D01*
Y88329D01*
X642980Y87650D01*
Y85550D01*
X643660Y84870D01*
Y82770D01*
X642980Y82091D01*
Y19448D01*
G03X643566Y18034I1999J0D01*
G01X644182Y17418D01*
G03X645596Y16832I1414J1413D01*
G01X647107D01*
X649173Y18898D01*
G01X664921Y29922D02*
Y31156D01*
X665752Y31987D01*
X667412D01*
G03X668912Y32608I0J2122D01*
G03X669532Y34106I-1500J1498D01*
G01Y54700D01*
X670259Y57679D01*
X671738Y61238D01*
X680105Y69605D01*
G02X681300Y70100I1195J-1195D01*
G03X682496Y70595I1J1690D01*
G01X683137Y71237D01*
X684099D01*
X685584Y72722D01*
Y73684D01*
X687107Y75207D01*
X688069D01*
X689554Y76692D01*
Y77653D01*
X691077Y79176D01*
Y79178D01*
X692039D01*
X693524Y80662D01*
Y81624D01*
X694538Y82638D01*
G02X694976Y82820I438J-436D01*
G01X695904D01*
X696584Y82140D01*
X698684D01*
X699364Y82820D01*
X700172D01*
G03X702562Y83810I0J3380D01*
G01X703022Y84270D01*
X703970D01*
X705455Y85755D01*
Y86703D01*
X706110Y87358D01*
G03X707100Y89748I-2390J2390D01*
G01Y92872D01*
G03X706513Y94287I-1999J0D01*
G01X706096Y94704D01*
G03X704682Y95290I-1414J-1413D01*
G01X703480D01*
X701670Y97100D01*
G01X680612Y129600D02*
X682422Y127790D01*
Y108006D01*
G03X683412Y105616I3380J0D01*
G01X683738Y105290D01*
G02X683920Y104852I-436J-438D01*
G01Y88103D01*
G02X683917Y88041I-620J-1D01*
G02X683873Y87866I-617J62D01*
G01X682828Y85347D01*
G02X682694Y85146I-573J237D01*
G01X664396Y66848D01*
G03X664244Y66620I495J-495D01*
G01X661446Y59844D01*
G03X661412Y59739I647J-267D01*
G01X660740Y56924D01*
X660357Y55320D01*
X660320Y55000D01*
Y29019D01*
G02X660094Y28474I-770J0D01*
G01X660075Y28455D01*
G02X659578Y28249I-496J495D01*
G01X657772D01*
X657047Y28974D01*
Y30315D01*
G01X685612Y129600D02*
X683802Y127790D01*
Y123901D01*
X684482Y123221D01*
Y121121D01*
X683802Y120441D01*
Y112887D01*
X684482Y112207D01*
Y110107D01*
X683802Y109427D01*
Y108006D01*
G03X684388Y106592I1999J0D01*
G01X684714Y106266D01*
G02X685300Y104852I-1413J-1414D01*
G01Y103234D01*
X685980Y102554D01*
Y100454D01*
X685300Y99774D01*
Y97619D01*
X685980Y96939D01*
Y94839D01*
X685300Y94159D01*
Y92005D01*
X685980Y91325D01*
Y89225D01*
X685300Y88545D01*
Y88103D01*
G02X685290Y87903I-2000J0D01*
G01X685148Y87338D01*
X684103Y84818D01*
G02X683670Y84170I-1848J766D01*
G01X683211Y83711D01*
X683210D01*
Y83709D01*
X682413Y82912D01*
X682411D01*
Y81950D01*
X680927Y80465D01*
X679966D01*
X665468Y65968D01*
X662743Y59366D01*
X661700Y55000D01*
Y29018D01*
G02X661070Y27498I-2150J1D01*
G01X661051Y27479D01*
G02X659578Y26869I-1472J1471D01*
G01X657800D01*
X657047Y26116D01*
Y24803D01*
G01X724400Y105600D02*
X726210Y107410D01*
Y108582D01*
G03X726028Y109020I-618J0D01*
G01X725210Y109838D01*
G03X724772Y110020I-438J-436D01*
G01X721948D01*
G03X720534Y109434I0J-1999D01*
G01X716986Y105886D01*
G03X716400Y104472I1413J-1414D01*
G01Y103209D01*
X717080Y102529D01*
Y100429D01*
X716400Y99749D01*
Y97609D01*
X717080Y96929D01*
Y94829D01*
X716400Y94149D01*
Y91894D01*
G02X716248Y91128I-2000J-1D01*
G01X712522Y82137D01*
G02X712089Y81489I-1848J766D01*
G01X707560Y76960D01*
G02X706912Y76527I-1414J1415D01*
G01X703844Y75255D01*
G02X703165Y75120I-679J1640D01*
G01X702048D01*
G03X700634Y74534I0J-1999D01*
G01X699380Y73280D01*
Y72430D01*
X697895Y70945D01*
X697045D01*
X690601Y64501D01*
G02X689953Y64068I-1414J1415D01*
G01X686718Y62727D01*
G02X686079Y62600I-639J1544D01*
G01X685028D01*
G03X683614Y62014I0J-1999D01*
G01X678153Y56553D01*
X677406Y54749D01*
Y45492D01*
G02X676794Y44016I-2088J1D01*
G01X676793Y44015D01*
G02X675320Y43405I-1472J1471D01*
G01X673226D01*
X672795Y42974D01*
Y41339D01*
G01X729400Y105600D02*
X727590Y107410D01*
Y108582D01*
G03X727004Y109996I-1999J0D01*
G01X726187Y110813D01*
G03X724772Y111400I-1415J-1412D01*
G01X721948D01*
G03X719558Y110410I0J-3380D01*
G01X716010Y106862D01*
G03X715020Y104472I2390J-2390D01*
G01Y91893D01*
G02X714972Y91656I-620J2D01*
G01X711247Y82665D01*
G02X711113Y82465I-573J239D01*
G01X706584Y77936D01*
G02X706383Y77802I-438J439D01*
G01X703316Y76530D01*
G02X703165Y76500I-151J365D01*
G01X702048D01*
G03X699658Y75510I0J-3380D01*
G01X689625Y65477D01*
G02X689424Y65344I-436J440D01*
G01X686190Y64002D01*
G02X686079Y63980I-111J269D01*
G01X685028D01*
G03X682638Y62990I0J-3380D01*
G01X676983Y57335D01*
X676026Y55024D01*
Y45493D01*
G02X675818Y44992I-708J0D01*
G01X675817Y44991D01*
G02X675320Y44785I-496J495D01*
G01X673526D01*
X672795Y45516D01*
Y46851D01*
G01X701670Y92100D02*
X703480Y93910D01*
X704682D01*
G02X705120Y93728I0J-618D01*
G01X705538Y93310D01*
G02X705720Y92872I-436J-438D01*
G01Y89748D01*
G02X705134Y88334I-1999J0D01*
G01X701586Y84786D01*
G02X700172Y84200I-1414J1413D01*
G01X694976D01*
G03X693562Y83614I0J-1999D01*
G01X681519Y71571D01*
G02X681300Y71480I-219J218D01*
G03X679129Y70581I0J-3071D01*
G01X670666Y62119D01*
G03X670515Y61893I495J-494D01*
G01X668964Y58160D01*
G03X668930Y58057I646J-270D01*
G01X668887Y57884D01*
X668494Y56271D01*
X668191Y55027D01*
X668152Y54700D01*
Y34106D01*
G02X667936Y33584I-739J0D01*
G02X667412Y33367I-524J524D01*
G01X665652D01*
X664921Y34098D01*
Y35433D01*
G01X677638Y93290D02*
X675828Y95100D01*
Y97950D01*
X675167Y99333D01*
X673587Y100913D01*
G03X672172Y101500I-1415J-1412D01*
G01X669848D01*
G03X667458Y100510I0J-3380D01*
G01X666490Y99542D01*
G03X665520Y97200I2342J-2342D01*
G02X665358Y96810I-550J0D01*
G01X653410Y84862D01*
G03X652420Y82472I2390J-2390D01*
G01Y45494D01*
G03X653032Y44016I2091J0D01*
G03X654508Y43405I1476J1477D01*
G01X656395D01*
X657047Y42753D01*
Y41339D01*
G01X672638Y93290D02*
X674448Y95100D01*
Y97637D01*
X674024Y98524D01*
X672610Y99938D01*
G03X672172Y100120I-438J-436D01*
G01X669848D01*
G03X668434Y99534I0J-1999D01*
G01X667466Y98566D01*
G03X666900Y97200I1365J-1366D01*
G02X666334Y95834I-1931J0D01*
G01X654386Y83886D01*
G03X653800Y82472I1413J-1414D01*
G01Y81494D01*
X654480Y80814D01*
Y78714D01*
X653800Y78034D01*
Y75934D01*
X654480Y75254D01*
Y73154D01*
X653800Y72474D01*
Y70374D01*
X654480Y69694D01*
Y67594D01*
X653800Y66914D01*
Y45494D01*
G03X654008Y44992I710J0D01*
G03X654508Y44785I500J500D01*
G01X656585D01*
X657047Y45247D01*
Y46851D01*
G01X745905Y120452D02*
X747715Y118642D01*
Y114824D01*
G02X747533Y114386I-618J0D01*
G01X738515Y105369D01*
G02X738491Y105347I-430J445D01*
G01X738489Y105345D01*
X729979Y97735D01*
X729972Y97729D01*
X714900Y74001D01*
X705189Y68014D01*
X705167Y67997D01*
G03X705155Y67987I442J-543D01*
G01X691900Y57300D01*
X687628Y56400D01*
G03X686213Y55813I0J-1999D01*
G01X684506Y54106D01*
G03X683920Y52692I1413J-1414D01*
G01Y17828D01*
G02X683738Y17390I-618J0D01*
G01X683362Y17014D01*
G02X682924Y16832I-438J436D01*
G01X681400D01*
X680669Y17563D01*
Y18898D01*
G01X750905Y120452D02*
X749095Y118642D01*
Y114824D01*
G02X748509Y113410I-1999J0D01*
G01X746986Y111887D01*
Y110925D01*
X745501Y109440D01*
X744539D01*
X743016Y107917D01*
Y106956D01*
X741530Y105470D01*
X740569D01*
X739489Y104390D01*
G02X739408Y104314I-1408J1420D01*
G01X731034Y96827D01*
X728302Y92525D01*
X728267Y92518D01*
X728478Y91579D01*
X727354Y89806D01*
X726415Y89596D01*
X726423Y89566D01*
X725288Y87779D01*
X725262Y87775D01*
X725473Y86837D01*
X724349Y85063D01*
X723410Y84853D01*
X723415Y84832D01*
Y84831D01*
X722274Y83034D01*
X722273Y83035D01*
X722256Y83032D01*
X722467Y82094D01*
X721344Y80320D01*
X720405Y80109D01*
X720408Y80098D01*
X719258Y78287D01*
X719252Y78290D01*
X719463Y77352D01*
X718338Y75578D01*
X717400Y75368D01*
X717402Y75363D01*
X715900Y72995D01*
X705988Y66884D01*
X692509Y56017D01*
X687772Y55020D01*
X687628D01*
G03X687190Y54838I0J-618D01*
G01X685482Y53130D01*
G03X685300Y52692I436J-438D01*
G01Y17828D01*
G02X684713Y16413I-1999J0D01*
G01X684338Y16038D01*
G02X682924Y15452I-1414J1413D01*
G01X681652D01*
X680669Y14469D01*
Y13386D01*
G01X764803Y120330D02*
X766613Y118520D01*
Y105921D01*
G02X766431Y105483I-618J0D01*
G01X759410Y98462D01*
G03X758420Y96072I2390J-2390D01*
G01Y87628D01*
G02X758238Y87190I-618J0D01*
G01X699479Y28431D01*
G02X699041Y28249I-438J436D01*
G01X690609D01*
X688543Y30315D01*
G01X769803Y120330D02*
X767993Y118520D01*
Y105921D01*
G02X767407Y104507I-1999J0D01*
G01X760386Y97486D01*
G03X759800Y96072I1413J-1414D01*
G01Y87628D01*
G02X759214Y86214I-1999J0D01*
G01X744175Y71175D01*
Y70213D01*
X742690Y68728D01*
X741728D01*
X740205Y67205D01*
Y66243D01*
X738720Y64758D01*
X737759D01*
X736235Y63235D01*
Y62273D01*
X734750Y60788D01*
X733788D01*
X732265Y59265D01*
Y58303D01*
X730780Y56818D01*
X729819D01*
X728295Y55295D01*
Y54334D01*
X726810Y52848D01*
X725848D01*
X723432Y50432D01*
Y49470D01*
X721947Y47985D01*
X720985D01*
X700455Y27455D01*
G02X699041Y26869I-1414J1413D01*
G01X690609D01*
X688543Y24803D01*
G01X1531692Y121000D02*
X1533503Y122811D01*
Y124068D01*
G03X1533321Y124506I-618J0D01*
G01X1533289Y124538D01*
G03X1532851Y124720I-438J-436D01*
G01X1530527D01*
G03X1529113Y124134I0J-1999D01*
G01X1525145Y120166D01*
G03X1524559Y118752I1413J-1414D01*
G01Y107108D01*
G02X1523973Y105694I-1999J0D01*
G01X1513645Y95366D01*
G03X1513059Y93952I1413J-1414D01*
G01Y91108D01*
X1513739Y90429D01*
Y88329D01*
X1513059Y87650D01*
Y85550D01*
X1513739Y84870D01*
Y82770D01*
X1513059Y82091D01*
Y19448D01*
G03X1513645Y18034I1999J0D01*
G01X1514261Y17418D01*
G03X1515675Y16832I1414J1413D01*
G01X1517186D01*
X1519252Y18898D01*
G01X1527126Y24803D02*
Y26116D01*
X1527879Y26869D01*
X1529657D01*
G03X1531130Y27479I1J2081D01*
G01X1531149Y27498D01*
G03X1531779Y29018I-1520J1521D01*
G01Y55000D01*
X1532822Y59366D01*
X1535547Y65968D01*
X1550045Y80465D01*
X1551006D01*
X1552490Y81950D01*
Y82912D01*
X1552492D01*
X1553289Y83709D01*
Y83711D01*
X1553290D01*
X1553749Y84170D01*
G03X1554182Y84818I-1415J1414D01*
G01X1555227Y87338D01*
X1555369Y87903D01*
X1555370Y87905D01*
X1555379Y88545D01*
X1556059Y89225D01*
Y91325D01*
X1555379Y92005D01*
Y94159D01*
X1556059Y94839D01*
Y96939D01*
X1555379Y97619D01*
Y99774D01*
X1556059Y100454D01*
Y102554D01*
X1555379Y103234D01*
Y104852D01*
G03X1554793Y106266I-1999J0D01*
G01X1554467Y106592D01*
G02X1553881Y108006I1413J1414D01*
G01Y109427D01*
X1554561Y110107D01*
Y112207D01*
X1553881Y112887D01*
Y120441D01*
X1554561Y121121D01*
Y123221D01*
X1553881Y123901D01*
Y127791D01*
X1555690Y129600D01*
G01X1550690D02*
X1552501Y127789D01*
Y108006D01*
G03X1553491Y105616I3380J0D01*
G01X1553817Y105290D01*
G02X1553999Y104852I-436J-438D01*
G01Y88564D01*
X1553992Y88087D01*
X1553940Y87884D01*
X1553952Y87866D01*
X1552907Y85347D01*
G02X1552773Y85146I-573J237D01*
G01X1534475Y66848D01*
G03X1534323Y66620I495J-495D01*
G01X1531525Y59844D01*
G03X1531491Y59739I647J-267D01*
G01X1530819Y56924D01*
X1530436Y55320D01*
X1530399Y55000D01*
Y29019D01*
G02X1530173Y28474I-770J0D01*
G01X1530154Y28455D01*
G02X1529657Y28249I-496J495D01*
G01X1527851D01*
X1527126Y28974D01*
Y30315D01*
G01X1536692Y121000D02*
X1534883Y122809D01*
Y124068D01*
G03X1534297Y125482I-1999J0D01*
G01X1534266Y125513D01*
G03X1532851Y126100I-1415J-1412D01*
G01X1530527D01*
G03X1528137Y125110I0J-3380D01*
G01X1524169Y121142D01*
G03X1523179Y118752I2390J-2390D01*
G01Y107108D01*
G02X1522997Y106670I-618J0D01*
G01X1512669Y96342D01*
G03X1511679Y93952I2390J-2390D01*
G01Y19448D01*
G03X1512669Y17058I3380J0D01*
G01X1513285Y16442D01*
G03X1515675Y15452I2390J2390D01*
G01X1517186D01*
X1519252Y13386D01*
G01X1527126Y46851D02*
Y45247D01*
X1526664Y44785D01*
X1524587D01*
G02X1524087Y44992I0J707D01*
G02X1523879Y45494I502J502D01*
G01Y66914D01*
X1524559Y67594D01*
Y69694D01*
X1523879Y70374D01*
Y72474D01*
X1524559Y73154D01*
Y75254D01*
X1523879Y75934D01*
Y78034D01*
X1524559Y78714D01*
Y80814D01*
X1523879Y81494D01*
Y82472D01*
G02X1524465Y83886I1999J0D01*
G01X1536413Y95834D01*
G03X1536979Y97200I-1365J1366D01*
G02X1537545Y98566I1931J0D01*
G01X1538513Y99534D01*
G02X1539927Y100120I1414J-1413D01*
G01X1542251D01*
G02X1542689Y99938I0J-618D01*
G01X1544103Y98524D01*
X1544527Y97637D01*
Y95101D01*
X1542716Y93290D01*
G01X1547716D02*
X1545907Y95099D01*
Y97950D01*
X1545246Y99333D01*
X1543666Y100913D01*
G03X1542251Y101500I-1415J-1412D01*
G01X1539927D01*
G03X1537537Y100510I0J-3380D01*
G01X1536569Y99542D01*
G03X1535599Y97200I2342J-2342D01*
G02X1535437Y96810I-550J0D01*
G01X1523489Y84862D01*
G03X1522499Y82472I2390J-2390D01*
G01Y45494D01*
G03X1523111Y44016I2091J0D01*
G03X1524587Y43405I1476J1477D01*
G01X1526474D01*
X1527126Y42753D01*
Y41339D01*
G01X1535000Y29922D02*
Y31156D01*
X1535831Y31987D01*
X1537491D01*
G03X1538991Y32608I0J2122D01*
G03X1539611Y34106I-1500J1498D01*
G01Y54700D01*
X1540338Y57679D01*
X1541817Y61238D01*
X1550184Y69605D01*
G02X1551379Y70100I1195J-1195D01*
G03X1552575Y70595I1J1690D01*
G01X1553216Y71237D01*
X1554178D01*
X1555663Y72722D01*
Y73684D01*
X1557186Y75207D01*
X1558148D01*
X1559633Y76692D01*
Y77653D01*
X1561156Y79176D01*
Y79178D01*
X1562118D01*
X1563603Y80662D01*
Y81624D01*
X1564617Y82638D01*
G02X1565055Y82820I438J-436D01*
G01X1565983D01*
X1566663Y82140D01*
X1568763D01*
X1569443Y82820D01*
X1570251D01*
G03X1572641Y83810I0J3380D01*
G01X1573101Y84270D01*
X1574049D01*
X1575534Y85755D01*
Y86703D01*
X1576189Y87358D01*
G03X1577179Y89748I-2390J2390D01*
G01Y92872D01*
G03X1576592Y94287I-1999J0D01*
G01X1576175Y94704D01*
G03X1574761Y95290I-1414J-1413D01*
G01X1573558D01*
X1571748Y97100D01*
G01Y92100D02*
X1573558Y93910D01*
X1574761D01*
G02X1575199Y93728I0J-618D01*
G01X1575617Y93310D01*
G02X1575799Y92872I-436J-438D01*
G01Y89748D01*
G02X1575213Y88334I-1999J0D01*
G01X1571665Y84786D01*
G02X1570251Y84200I-1414J1413D01*
G01X1565055D01*
G03X1563641Y83614I0J-1999D01*
G01X1551598Y71571D01*
G02X1551379Y71480I-219J218D01*
G03X1549208Y70581I0J-3071D01*
G01X1540745Y62119D01*
G03X1540594Y61893I495J-494D01*
G01X1539043Y58160D01*
G03X1539009Y58057I646J-270D01*
G01X1538966Y57884D01*
X1538573Y56271D01*
X1538270Y55027D01*
X1538231Y54700D01*
Y34106D01*
G02X1538015Y33584I-739J0D01*
G02X1537491Y33367I-524J524D01*
G01X1535731D01*
X1535000Y34098D01*
Y35433D01*
G01X1599478Y105600D02*
X1597669Y107409D01*
Y108582D01*
G03X1597083Y109996I-1999J0D01*
G01X1596266Y110813D01*
G03X1594851Y111400I-1415J-1412D01*
G01X1592027D01*
G03X1589637Y110410I0J-3380D01*
G01X1586089Y106862D01*
G03X1585099Y104472I2390J-2390D01*
G01Y91893D01*
G02X1585051Y91656I-620J2D01*
G01X1581326Y82665D01*
G02X1581192Y82465I-573J239D01*
G01X1576663Y77936D01*
G02X1576462Y77802I-438J439D01*
G01X1573395Y76530D01*
G02X1573244Y76500I-151J365D01*
G01X1572127D01*
G03X1569737Y75510I0J-3380D01*
G01X1559704Y65477D01*
G02X1559503Y65344I-436J440D01*
G01X1556269Y64002D01*
G02X1556158Y63980I-111J269D01*
G01X1555107D01*
G03X1552717Y62990I0J-3380D01*
G01X1547062Y57335D01*
X1546105Y55024D01*
Y45493D01*
G02X1545897Y44992I-708J0D01*
G01X1545896Y44991D01*
G02X1545399Y44785I-496J495D01*
G01X1543605D01*
X1542874Y45516D01*
Y46851D01*
G01Y41339D02*
Y42974D01*
X1543305Y43405D01*
X1545399D01*
G03X1546872Y44015I1J2081D01*
G01X1546873Y44016D01*
G03X1547485Y45492I-1476J1477D01*
G01Y54749D01*
X1548232Y56553D01*
X1553693Y62014D01*
G02X1555107Y62600I1414J-1413D01*
G01X1556158D01*
G03X1556797Y62727I0J1671D01*
G01X1560032Y64068D01*
G03X1560680Y64501I-766J1848D01*
G01X1567124Y70945D01*
X1567974D01*
X1569459Y72430D01*
Y73280D01*
X1570713Y74534D01*
G02X1572127Y75120I1414J-1413D01*
G01X1573244D01*
G03X1573923Y75255I0J1775D01*
G01X1576991Y76527D01*
G03X1577639Y76960I-766J1848D01*
G01X1582168Y81489D01*
G03X1582601Y82137I-1415J1414D01*
G01X1586327Y91128D01*
G03X1586479Y91894I-1848J765D01*
G01Y94149D01*
X1587159Y94829D01*
Y96929D01*
X1586479Y97609D01*
Y99749D01*
X1587159Y100429D01*
Y102529D01*
X1586479Y103209D01*
Y104472D01*
G02X1587065Y105886I1999J0D01*
G01X1590613Y109434D01*
G02X1592027Y110020I1414J-1413D01*
G01X1594851D01*
G02X1595289Y109838I0J-618D01*
G01X1596107Y109020D01*
G02X1596289Y108582I-436J-438D01*
G01Y107411D01*
X1594478Y105600D01*
G01X1620983Y120452D02*
X1619174Y118643D01*
Y114824D01*
G02X1618588Y113410I-1999J0D01*
G01X1617065Y111887D01*
Y110925D01*
X1615580Y109440D01*
X1614618D01*
X1613095Y107917D01*
Y106956D01*
X1611609Y105470D01*
X1610648D01*
X1609568Y104390D01*
G02X1609487Y104314I-1408J1420D01*
G01X1601113Y96827D01*
X1598381Y92525D01*
X1598346Y92518D01*
X1598557Y91579D01*
X1597433Y89806D01*
X1596494Y89596D01*
X1596502Y89566D01*
X1595367Y87779D01*
X1595341Y87775D01*
X1595552Y86837D01*
X1594428Y85063D01*
X1593489Y84853D01*
X1593494Y84832D01*
Y84831D01*
X1592353Y83034D01*
X1592352Y83035D01*
X1592335Y83032D01*
X1592546Y82094D01*
X1591423Y80320D01*
X1590484Y80109D01*
X1590487Y80098D01*
X1589337Y78287D01*
X1589331Y78290D01*
X1589542Y77352D01*
X1588417Y75578D01*
X1587479Y75368D01*
X1587481Y75363D01*
X1585979Y72995D01*
X1576067Y66884D01*
X1562588Y56017D01*
X1557851Y55020D01*
X1557707D01*
G03X1557269Y54838I0J-618D01*
G01X1555561Y53130D01*
G03X1555379Y52692I436J-438D01*
G01Y17828D01*
G02X1554792Y16413I-1999J0D01*
G01X1554417Y16038D01*
G02X1553003Y15452I-1414J1413D01*
G01X1551731D01*
X1550748Y14469D01*
Y13386D01*
G01X1639881Y120330D02*
X1638072Y118521D01*
Y105921D01*
G02X1637486Y104507I-1999J0D01*
G01X1630465Y97486D01*
G03X1629879Y96072I1413J-1414D01*
G01Y87628D01*
G02X1629293Y86214I-1999J0D01*
G01X1614254Y71175D01*
Y70213D01*
X1612769Y68728D01*
X1611807D01*
X1610284Y67205D01*
Y66243D01*
X1608799Y64758D01*
X1607838D01*
X1606314Y63235D01*
Y62273D01*
X1604829Y60788D01*
X1603867D01*
X1602344Y59265D01*
Y58303D01*
X1600859Y56818D01*
X1599898D01*
X1598374Y55295D01*
Y54334D01*
X1596889Y52848D01*
X1595927D01*
X1593511Y50432D01*
Y49470D01*
X1592026Y47985D01*
X1591064D01*
X1570534Y27455D01*
G02X1569120Y26869I-1414J1413D01*
G01X1560688D01*
X1558622Y24803D01*
G01X1615983Y120452D02*
X1617794Y118641D01*
Y114824D01*
G02X1617612Y114386I-618J0D01*
G01X1608594Y105369D01*
G02X1608570Y105347I-430J445D01*
G01X1608568Y105345D01*
X1600058Y97735D01*
X1600051Y97729D01*
X1584979Y74001D01*
X1575268Y68014D01*
X1575246Y67997D01*
G03X1575234Y67987I442J-542D01*
G01X1561979Y57300D01*
X1557707Y56400D01*
G03X1556292Y55813I0J-1999D01*
G01X1554585Y54106D01*
G03X1553999Y52692I1413J-1414D01*
G01Y17828D01*
G02X1553817Y17390I-618J0D01*
G01X1553441Y17014D01*
G02X1553003Y16832I-438J436D01*
G01X1551479D01*
X1550748Y17563D01*
Y18898D01*
G01X1634881Y120330D02*
X1636692Y118519D01*
Y105921D01*
G02X1636510Y105483I-618J0D01*
G01X1629489Y98462D01*
G03X1628499Y96072I2390J-2390D01*
G01Y87628D01*
G02X1628317Y87190I-618J0D01*
G01X1569558Y28431D01*
G02X1569120Y28249I-438J436D01*
G01X1560688D01*
X1558622Y30315D01*
G54D36*
X452875Y131650D03*
X455867Y153658D03*
X452875Y194642D03*
X516851Y140666D03*
X519843Y115666D03*
Y194642D03*
X1322954Y131650D03*
Y194642D03*
X1325946Y153658D03*
X1389922Y115666D03*
X1386930Y140666D03*
X1389922Y194642D03*
G54D18*
X56339Y135827D03*
G54D27*
X343780Y11810D03*
Y19684D03*
Y27558D03*
X335906Y11810D03*
Y19684D03*
Y27558D03*
X343780Y43306D03*
Y51180D03*
X335906Y43306D03*
Y51180D03*
X343780Y59054D03*
X367402Y11810D03*
Y19684D03*
Y27558D03*
X359528Y11810D03*
Y19684D03*
Y27558D03*
X367402Y43306D03*
Y51180D03*
X359528Y43306D03*
Y51180D03*
X367402Y59054D03*
X359528D03*
X1205984Y11810D03*
Y19684D03*
Y27558D03*
Y43306D03*
Y51180D03*
X1213858Y11810D03*
Y19684D03*
Y27558D03*
X1229606Y11810D03*
Y19684D03*
Y27558D03*
Y43306D03*
Y51180D03*
X1213858Y43306D03*
Y51180D03*
X1229606Y59054D03*
X1213858D03*
X1237480Y11810D03*
Y19684D03*
Y27558D03*
Y43306D03*
Y51180D03*
Y59054D03*
G54D46*
G01X474528Y30315D02*
Y28731D01*
X475100Y28159D01*
X477264D01*
X478300Y29195D01*
Y55200D01*
X473300Y60200D01*
Y92998D01*
X474782Y94480D01*
Y95382D01*
X476012Y96612D01*
X476914D01*
X478144Y97842D01*
Y98744D01*
X479374Y99974D01*
X480276D01*
X481506Y101204D01*
Y102106D01*
X482736Y103336D01*
X483638D01*
X492700Y112398D01*
Y118502D01*
X490328Y120874D01*
X487980D01*
X487840Y120734D01*
X487666Y120647D01*
X487147Y120388D01*
X486887Y119610D01*
X488859Y115666D01*
G01X474528Y24803D02*
Y26187D01*
X475300Y26959D01*
X477762D01*
X479500Y28697D01*
Y55698D01*
X474500Y60698D01*
Y92500D01*
X493900Y111900D01*
Y119000D01*
X490826Y122074D01*
X487482D01*
X487129Y121721D01*
X486610Y121462D01*
X485832Y121720D01*
X483859Y125666D01*
G01X488859Y141650D02*
X486887Y145594D01*
X487147Y146372D01*
X487666Y146631D01*
X487840Y146718D01*
X487980Y146858D01*
X490744D01*
X493500Y144102D01*
Y138802D01*
X499902Y132400D01*
X503600D01*
X508500Y127500D01*
Y117398D01*
X502000Y110898D01*
Y98898D01*
X496500Y93398D01*
Y58798D01*
X493634Y55932D01*
Y16824D01*
X494916Y15542D01*
X497358D01*
X498150Y14750D01*
Y13386D01*
G01X483859Y151650D02*
X485832Y147704D01*
X486610Y147446D01*
X487129Y147705D01*
X487482Y148058D01*
X491242D01*
X494700Y144600D01*
Y139300D01*
X500400Y133600D01*
X504098D01*
X509700Y127998D01*
Y116900D01*
X503200Y110400D01*
Y98400D01*
X497700Y92900D01*
Y90003D01*
X498300Y89403D01*
Y87663D01*
X497700Y87063D01*
Y85323D01*
X498300Y84723D01*
Y82983D01*
X497700Y82383D01*
Y80643D01*
X498300Y80043D01*
Y78303D01*
X497700Y77703D01*
Y75963D01*
X498300Y75363D01*
Y73623D01*
X497700Y73023D01*
Y58300D01*
X494834Y55434D01*
Y17322D01*
X495414Y16742D01*
X497442D01*
X498150Y17450D01*
Y18898D01*
G01X1344607Y30315D02*
Y28552D01*
X1345000Y28159D01*
X1347343D01*
X1348379Y29195D01*
Y92877D01*
X1352261Y96759D01*
Y97661D01*
X1353491Y98891D01*
X1354393D01*
X1355623Y100121D01*
Y101023D01*
X1356853Y102253D01*
X1357755D01*
X1358985Y103483D01*
Y104385D01*
X1360215Y105615D01*
X1361117D01*
X1362600Y107098D01*
Y119402D01*
X1360902Y121100D01*
X1358285D01*
X1357919Y120734D01*
X1357745Y120647D01*
X1357226Y120388D01*
X1356966Y119610D01*
X1358938Y115666D01*
G01X1344607Y24803D02*
Y26466D01*
X1345100Y26959D01*
X1347841D01*
X1349579Y28697D01*
Y92379D01*
X1363800Y106600D01*
Y119900D01*
X1361400Y122300D01*
X1357787D01*
X1357208Y121721D01*
X1356689Y121462D01*
X1355911Y121720D01*
X1353938Y125666D01*
G01Y151650D02*
X1355911Y147704D01*
X1356689Y147446D01*
X1357208Y147705D01*
X1357561Y148058D01*
X1361442D01*
X1364600Y144900D01*
Y138900D01*
X1368100Y135400D01*
X1372377D01*
X1379779Y127998D01*
Y102110D01*
X1380400Y101490D01*
Y99750D01*
X1379779Y99130D01*
Y97390D01*
X1380400Y96770D01*
Y95030D01*
X1379779Y94410D01*
Y92670D01*
X1380400Y92050D01*
Y90310D01*
X1379779Y89690D01*
Y87950D01*
X1380400Y87330D01*
Y85590D01*
X1379779Y84970D01*
Y72679D01*
X1364913Y57813D01*
Y17322D01*
X1365493Y16742D01*
X1367642D01*
X1368229Y17329D01*
Y18898D01*
G01X1358938Y141650D02*
X1356966Y145594D01*
X1357226Y146372D01*
X1357919Y146718D01*
X1358059Y146858D01*
X1360944D01*
X1363400Y144402D01*
Y138402D01*
X1367602Y134200D01*
X1371879D01*
X1378579Y127500D01*
Y73177D01*
X1363713Y58311D01*
Y16824D01*
X1364995Y15542D01*
X1367558D01*
X1368229Y14871D01*
Y13386D01*
G54D37*
X463859Y176650D03*
X508859D03*
X1333938D03*
X1378938D03*
G54D28*
X351654Y37400D03*
X1221732D03*
G54D19*
X51900Y162300D03*
X53200Y169500D03*
X76900Y20200D03*
X65600Y160400D03*
X57200Y165300D03*
X73200Y162100D03*
X62200Y169900D03*
X70400Y170000D03*
X90200Y22400D03*
X94900Y144500D03*
X83800Y154500D03*
X99000Y148900D03*
X78800Y158000D03*
X93900Y162900D03*
X90200Y169500D03*
X81600Y162600D03*
X92600Y154800D03*
X100700Y163400D03*
X89000Y150200D03*
X88000Y158900D03*
X83500Y169700D03*
X78200Y169900D03*
X96900Y169500D03*
X98000Y157100D03*
X102500Y29400D03*
X107200Y19300D03*
X109500Y41000D03*
X121200Y33900D03*
X123100Y49600D03*
X102000Y141900D03*
X114000Y145200D03*
X119900Y143200D03*
X108600Y143100D03*
X111800Y151800D03*
X104900Y157400D03*
X120500Y157200D03*
X111900Y164800D03*
X118100Y162100D03*
X104500Y150300D03*
X110900Y159200D03*
X118400Y152000D03*
X106500Y170300D03*
X115300Y170200D03*
X143300Y27300D03*
X123900Y41000D03*
X143800Y53600D03*
X144500Y40000D03*
X138700Y63500D03*
X144100Y72900D03*
X133100Y71300D03*
X139800Y90200D03*
X131400Y91300D03*
X144200Y96300D03*
X129200Y101300D03*
X143000Y105700D03*
X129200Y142400D03*
X126600Y149500D03*
X141900Y154700D03*
X134800Y164000D03*
X144700Y149200D03*
X137100Y158600D03*
X137000Y170400D03*
X127400D03*
X165600Y19400D03*
X150300Y20200D03*
X168100Y48400D03*
X151500Y35800D03*
X166500Y34700D03*
X153100Y49600D03*
X159800Y65100D03*
X161800Y86800D03*
X148800Y85000D03*
X158200Y102400D03*
X163500Y144900D03*
X150300Y144600D03*
X156000Y138200D03*
X156500Y144800D03*
X169900Y146800D03*
X164400Y138200D03*
X169400Y153600D03*
X155600Y157900D03*
X162100Y164300D03*
X168000Y161200D03*
X149300Y164100D03*
X163200Y151600D03*
X162000Y159400D03*
X148000Y158800D03*
X152600Y152000D03*
X155900Y170000D03*
X163800Y170100D03*
X148600D03*
X180300Y20200D03*
X184100Y36600D03*
X183100Y49600D03*
X174300Y73300D03*
X191700Y75400D03*
X175000Y62300D03*
X181400Y84700D03*
X174200Y96300D03*
X190400Y136600D03*
X191200Y142400D03*
X178100Y144600D03*
X184000Y138800D03*
X173600Y138700D03*
X185800Y145400D03*
X190000Y149800D03*
X179300Y156400D03*
X187100Y155800D03*
X192100Y163500D03*
X176300Y164400D03*
X175500Y151300D03*
X173700Y158700D03*
X190400Y169800D03*
X182600Y152000D03*
X171300Y170000D03*
X177800Y170400D03*
X194400Y20200D03*
X197800Y30900D03*
X210300Y20200D03*
X197800Y48000D03*
X214700Y35800D03*
X213100Y49600D03*
X195600Y64100D03*
X206700Y72700D03*
X209400Y60900D03*
X204200Y96300D03*
X196200Y102300D03*
X211300Y138600D03*
X204200Y139200D03*
X195900Y146300D03*
X213300Y146800D03*
X197300Y139100D03*
X205100Y147700D03*
X201500Y154400D03*
X213500Y155400D03*
X197100Y160800D03*
X194600Y154800D03*
X225800Y19600D03*
X229200Y30900D03*
X227100Y43000D03*
X216400Y100500D03*
X234200Y96300D03*
X225600Y104500D03*
X234500Y138700D03*
X230600Y146400D03*
X218100Y140500D03*
X224400Y138200D03*
X236800Y165000D03*
X238800Y157500D03*
X231600Y155100D03*
X221800Y149400D03*
X236500Y185900D03*
X235400Y172900D03*
X254400Y19200D03*
X240300Y20200D03*
X257800Y51200D03*
X244900Y36600D03*
X243100Y49600D03*
X254400Y74300D03*
X251600Y100100D03*
X248600Y142900D03*
X242600Y140100D03*
X254400Y138200D03*
X252200Y159400D03*
X239600Y148700D03*
X245100Y165200D03*
X255400Y148400D03*
X245600Y157000D03*
X248400Y149800D03*
X252800Y179900D03*
X239800Y178700D03*
X243300Y185600D03*
X242300Y171800D03*
X252600Y192000D03*
X242400Y193300D03*
X270300Y20200D03*
X268300Y36200D03*
X273100Y49600D03*
X283600Y69500D03*
X273300Y94900D03*
X264200Y96300D03*
X281800Y100900D03*
X262900Y104900D03*
X267700Y145200D03*
X284400Y138200D03*
X280000Y159800D03*
X281000Y180700D03*
X265300Y170000D03*
X282600Y192000D03*
X294200Y96300D03*
X307800Y101100D03*
X300300Y140000D03*
X287600Y150000D03*
X292800Y169800D03*
X324200Y96300D03*
X314600Y104100D03*
X310200Y135900D03*
X350000Y161800D03*
X338300Y162900D03*
X350200Y181100D03*
X338300Y183800D03*
X359200Y164900D03*
X359100Y184400D03*
X806800Y26700D03*
X813700Y43900D03*
X810700Y65200D03*
X809700Y86500D03*
X836800Y26700D03*
X825200Y111700D03*
X840700Y65200D03*
X839700Y86500D03*
X855200Y111700D03*
X838300Y128100D03*
X855400Y152400D03*
X857000Y189800D03*
X855400Y173000D03*
X866800Y26700D03*
X870700Y65200D03*
X869700Y86500D03*
X868300Y128100D03*
X896800Y26700D03*
X900700Y65200D03*
X899700Y86500D03*
X885200Y111700D03*
X898300Y128100D03*
X885400Y152400D03*
X887000Y189800D03*
X885400Y173000D03*
X926800Y26700D03*
X929700Y86500D03*
X915200Y111700D03*
X928300Y128100D03*
X915400Y152400D03*
X917000Y189800D03*
X915400Y173000D03*
X930700Y65200D03*
X945200Y111700D03*
X945400Y152400D03*
X947000Y189800D03*
X945400Y173000D03*
X959000Y18000D03*
X956800Y26700D03*
X960700Y65200D03*
X959700Y86500D03*
X975200Y111700D03*
X958300Y128100D03*
X975400Y152400D03*
Y173000D03*
X986800Y26700D03*
X990700Y65200D03*
X989700Y86500D03*
X988300Y128100D03*
X977000Y189800D03*
X1018800Y26300D03*
X1009800Y81300D03*
X1005200Y111700D03*
X1018300Y128100D03*
X1005400Y152400D03*
X1007000Y189800D03*
X1005400Y173000D03*
X1043000Y45500D03*
X1022700Y64800D03*
X1031900Y84100D03*
X1037200Y111300D03*
X1035400Y152400D03*
X1037000Y189800D03*
X1035400Y173000D03*
X1063700Y15300D03*
X1048800Y26300D03*
X1052700Y64800D03*
X1061900Y84100D03*
X1067200Y111300D03*
X1048300Y128100D03*
X1065400Y152400D03*
X1067000Y189800D03*
X1067400Y172600D03*
X1078800Y26300D03*
X1073000Y45500D03*
X1082700Y64800D03*
X1078300Y128100D03*
X1091900Y84100D03*
X1097200Y111300D03*
X1108300Y128100D03*
X1095400Y152400D03*
X1097000Y189800D03*
X1097400Y172600D03*
X1136600Y19700D03*
X1135400Y41000D03*
X1120900Y64500D03*
X1121900Y84100D03*
X1127200Y111300D03*
X1125400Y152400D03*
X1127000Y189800D03*
X1127400Y172600D03*
X1147100Y64500D03*
X1151900Y84100D03*
X1155400Y152400D03*
X1157000Y189800D03*
X1157400Y172600D03*
X1636400Y43100D03*
G54D47*
G01X405531Y21960D02*
X403911Y23580D01*
Y25375D01*
G02X404192Y26054I961J0D01*
G01X404897Y26759D01*
G02X405576Y27040I679J-680D01*
G01X407522D01*
X407645Y26917D01*
G03X410728Y25640I3083J3083D01*
G01X411832D01*
G02X413246Y25054I0J-1999D01*
G01X413523Y24777D01*
G03X414192Y24500I669J669D01*
G01X416021D01*
G03X417358Y25054I0J1890D01*
G02X418772Y25640I1414J-1413D01*
G01X419732D01*
G02X421146Y25054I0J-1999D01*
G01X421473Y24727D01*
G03X422262Y24400I789J788D01*
G01X423916D01*
G03X425330Y24986I0J1999D01*
G01X425398Y25054D01*
G02X426812Y25640I1414J-1413D01*
G01X427532D01*
G02X428946Y25054I0J-1999D01*
G01X429273Y24727D01*
G03X430062Y24400I789J788D01*
G01X431956D01*
G03X433370Y24986I0J1999D01*
G01X433438Y25054D01*
G02X434852Y25640I1414J-1413D01*
G01X435832D01*
G02X437246Y25054I0J-1999D01*
G01X437573Y24727D01*
G03X438362Y24400I789J788D01*
G01X439996D01*
G03X441410Y24986I0J1999D01*
G01X441478Y25054D01*
G02X442892Y25640I1414J-1413D01*
G01X443932D01*
G02X445346Y25054I0J-1999D01*
G01X445673Y24727D01*
G03X446462Y24400I789J788D01*
G01X448172D01*
G03X449586Y24986I0J1999D01*
G01X449654Y25054D01*
G02X451068Y25640I1414J-1413D01*
G01X455412D01*
G03X456826Y26226I0J1999D01*
G01X461511Y30911D01*
G02X462925Y31497I1414J-1413D01*
G01X465079D01*
X466654Y29922D01*
G01X400531Y21960D02*
X401551Y22980D01*
Y25923D01*
G02X402137Y27337I1999J0D01*
G01X403614Y28814D01*
G02X405028Y29400I1414J-1413D01*
G01X407672D01*
G02X409086Y28814I0J-1999D01*
G01X409314Y28586D01*
G03X410728Y28000I1414J1413D01*
G01X454864D01*
G03X455543Y28281I0J961D01*
G01X459842Y32580D01*
G02X462925Y33857I3083J-3083D01*
G01X465078D01*
X466654Y35433D01*
G01X447880Y36200D02*
X449498Y37818D01*
Y38494D01*
G03X449083Y39417I-1422J-85D01*
G01X448986Y39514D01*
G02X448400Y40928I1413J1414D01*
G01Y42022D01*
G02X448950Y43350I1878J0D01*
G01X449064Y43464D01*
G03X449500Y44516I-1051J1052D01*
G01Y45132D01*
G02X450777Y48215I4360J0D01*
G01X451678Y49116D01*
G02X454761Y50393I3083J-3083D01*
G01X455565D01*
G03X456979Y50979I0J1999D01*
G01X457114Y51114D01*
G02X458528Y51700I1414J-1413D01*
G01X460291D01*
G02X461160Y51340I0J-1229D01*
G01X461520Y50980D01*
G03X462935Y50393I1415J1412D01*
G01X465078D01*
X466654Y51969D01*
G01X453480Y36200D02*
X451860Y37820D01*
Y45132D01*
G02X452446Y46546I1999J0D01*
G01X453347Y47447D01*
G02X454761Y48033I1414J-1413D01*
G01X465078D01*
X466654Y46457D01*
G01X523300Y15580D02*
X521980Y16900D01*
X513692D01*
G02X511081Y17981I0J3694D01*
G02X510000Y20592I2613J2611D01*
G01Y25561D01*
G03X509761Y26139I-818J0D01*
G03X509182Y26379I-579J-578D01*
G01X507600D01*
X506024Y24803D01*
G01X523300Y20580D02*
X522566Y19846D01*
G02X521152Y19260I-1414J1413D01*
G01X520068D01*
G02X518654Y19846I0J1999D01*
G01X518526Y19974D01*
G03X517112Y20560I-1414J-1413D01*
G01X516336D01*
G03X515011Y20011I0J-1873D01*
G01X514662Y19662D01*
G02X513692Y19260I-970J969D01*
G02X512750Y19650I0J1333D01*
G02X512360Y20592I943J942D01*
G01Y25561D01*
G03X511432Y27807I-3179J1D01*
G03X509182Y28739I-2249J-2247D01*
G01X507600D01*
X506024Y30315D01*
G01X573721Y22500D02*
X572401Y23820D01*
Y26471D01*
G03X571815Y27885I-1999J0D01*
G01X570786Y28914D01*
G03X569372Y29500I-1414J-1413D01*
G01X566868D01*
G03X563785Y28223I0J-4360D01*
G01X562048Y26486D01*
G02X560634Y25900I-1414J1413D01*
G01X533957D01*
G02X533278Y26181I0J961D01*
G01X515461Y43998D01*
G03X512378Y45275I-3083J-3083D01*
G01X507600D01*
X506024Y46851D01*
G01X568721Y22500D02*
X570041Y23820D01*
Y25923D01*
G03X569760Y26602I-961J0D01*
G01X569503Y26859D01*
G03X568824Y27140I-679J-680D01*
G01X566868D01*
G03X565454Y26554I0J-1999D01*
G01X563717Y24817D01*
G02X560634Y23540I-3083J3083D01*
G01X558975D01*
G03X557798Y23094I-1J-1775D01*
G03X557720Y23020I1182J-1324D01*
G02X556465Y22500I-1255J1254D01*
G01X554935D01*
G02X553680Y23020I0J1774D01*
G03X553602Y23094I-1260J-1250D01*
G03X552425Y23540I-1176J-1329D01*
G01X550675D01*
G03X549498Y23094I-1J-1775D01*
G03X549420Y23020I1182J-1324D01*
G02X548165Y22500I-1255J1254D01*
G01X546635D01*
G02X545380Y23020I0J1774D01*
G03X545302Y23094I-1260J-1250D01*
G03X544125Y23540I-1176J-1329D01*
G01X542475D01*
G03X541298Y23094I-1J-1775D01*
G03X541220Y23020I1182J-1324D01*
G02X539965Y22500I-1255J1254D01*
G01X538535D01*
G02X537280Y23020I0J1774D01*
G03X537255Y23044I-1241J-1268D01*
G01X537200Y23093D01*
G03X536025Y23540I-1177J-1327D01*
G01X533409D01*
G02X531995Y24126I0J1999D01*
G01X531296Y24825D01*
G03X529882Y25411I-1414J-1413D01*
G01X529738D01*
G02X528324Y25997I0J1999D01*
G01X527460Y26861D01*
G02X526874Y28275I1413J1414D01*
G01Y28419D01*
G03X526288Y29833I-1999J0D01*
G01X525424Y30697D01*
G03X524010Y31283I-1414J-1413D01*
G01X523766D01*
G02X522352Y31869I0J1999D01*
G01X521588Y32633D01*
G02X521002Y34047I1413J1414D01*
G01Y34291D01*
G03X520416Y35705I-1999J0D01*
G01X519552Y36569D01*
G03X518138Y37155I-1414J-1413D01*
G01X518094D01*
G02X516680Y37741I0J1999D01*
G01X515716Y38705D01*
G02X515130Y40119I1413J1414D01*
G01Y40163D01*
G03X514544Y41577I-1999J0D01*
G01X513792Y42329D01*
G03X512378Y42915I-1414J-1413D01*
G01X507600D01*
X506024Y41339D01*
G01X1270610Y21960D02*
X1271630Y22980D01*
Y25923D01*
G02X1272216Y27337I1999J0D01*
G01X1273693Y28814D01*
G02X1275107Y29400I1414J-1413D01*
G01X1277751D01*
G02X1279165Y28814I0J-1999D01*
G01X1279393Y28586D01*
G03X1280807Y28000I1414J1413D01*
G01X1324943D01*
G03X1325622Y28281I0J961D01*
G01X1329921Y32580D01*
G02X1333004Y33857I3083J-3083D01*
G01X1335157D01*
X1336733Y35433D01*
G01X1275610Y21960D02*
X1273990Y23580D01*
Y25375D01*
G02X1274271Y26054I961J0D01*
G01X1274976Y26759D01*
G02X1275655Y27040I679J-680D01*
G01X1277601D01*
X1277724Y26917D01*
G03X1280807Y25640I3083J3083D01*
G01X1281911D01*
G02X1283325Y25054I0J-1999D01*
G01X1283602Y24777D01*
G03X1284271Y24500I669J669D01*
G01X1286100D01*
G03X1287437Y25054I0J1890D01*
G02X1288851Y25640I1414J-1413D01*
G01X1289811D01*
G02X1291225Y25054I0J-1999D01*
G01X1291552Y24727D01*
G03X1292341Y24400I789J788D01*
G01X1293995D01*
G03X1295409Y24986I0J1999D01*
G01X1295477Y25054D01*
G02X1296891Y25640I1414J-1413D01*
G01X1297611D01*
G02X1299025Y25054I0J-1999D01*
G01X1299352Y24727D01*
G03X1300141Y24400I789J788D01*
G01X1302035D01*
G03X1303449Y24986I0J1999D01*
G01X1303517Y25054D01*
G02X1304931Y25640I1414J-1413D01*
G01X1305911D01*
G02X1307325Y25054I0J-1999D01*
G01X1307652Y24727D01*
G03X1308441Y24400I789J788D01*
G01X1310075D01*
G03X1311489Y24986I0J1999D01*
G01X1311557Y25054D01*
G02X1312971Y25640I1414J-1413D01*
G01X1314011D01*
G02X1315425Y25054I0J-1999D01*
G01X1315752Y24727D01*
G03X1316541Y24400I789J788D01*
G01X1318251D01*
G03X1319665Y24986I0J1999D01*
G01X1319733Y25054D01*
G02X1321147Y25640I1414J-1413D01*
G01X1325491D01*
G03X1326905Y26226I0J1999D01*
G01X1331590Y30911D01*
G02X1333004Y31497I1414J-1413D01*
G01X1335158D01*
X1336733Y29922D01*
G01X1317959Y36200D02*
X1319577Y37818D01*
Y38494D01*
G03X1319162Y39417I-1422J-85D01*
G01X1319065Y39514D01*
G02X1318479Y40928I1413J1414D01*
G01Y42022D01*
G02X1319029Y43350I1878J0D01*
G01X1319143Y43464D01*
G03X1319579Y44516I-1051J1052D01*
G01Y45132D01*
G02X1320856Y48215I4360J0D01*
G01X1321757Y49116D01*
G02X1324840Y50393I3083J-3083D01*
G01X1325644D01*
G03X1327058Y50979I0J1999D01*
G01X1327193Y51114D01*
G02X1328607Y51700I1414J-1413D01*
G01X1330370D01*
G02X1331239Y51340I0J-1229D01*
G01X1331599Y50980D01*
G03X1333014Y50393I1415J1412D01*
G01X1335157D01*
X1336733Y51969D01*
G01X1323559Y36200D02*
X1321939Y37820D01*
Y45132D01*
G02X1322525Y46546I1999J0D01*
G01X1323426Y47447D01*
G02X1324840Y48033I1414J-1413D01*
G01X1335157D01*
X1336733Y46457D01*
G01X1393379Y20580D02*
X1392645Y19846D01*
G02X1391231Y19260I-1414J1413D01*
G01X1390147D01*
G02X1388733Y19846I0J1999D01*
G01X1388605Y19974D01*
G03X1387191Y20560I-1414J-1413D01*
G01X1386415D01*
G03X1385090Y20011I0J-1873D01*
G01X1384741Y19662D01*
G02X1383771Y19260I-970J969D01*
G02X1382829Y19650I0J1333D01*
G02X1382439Y20592I943J942D01*
G01Y25561D01*
G03X1381511Y27807I-3179J1D01*
G03X1379261Y28739I-2249J-2247D01*
G01X1377679D01*
X1376103Y30315D01*
G01X1393379Y15580D02*
X1392059Y16900D01*
X1383771D01*
G02X1381160Y17981I0J3694D01*
G02X1380079Y20592I2613J2611D01*
G01Y25561D01*
G03X1379840Y26139I-818J0D01*
G03X1379261Y26379I-579J-578D01*
G01X1377679D01*
X1376103Y24803D01*
G01X1443800Y22500D02*
X1442480Y23820D01*
Y26471D01*
G03X1441894Y27885I-1999J0D01*
G01X1440865Y28914D01*
G03X1439451Y29500I-1414J-1413D01*
G01X1436947D01*
G03X1433864Y28223I0J-4360D01*
G01X1432127Y26486D01*
G02X1430713Y25900I-1414J1413D01*
G01X1404036D01*
G02X1403357Y26181I0J961D01*
G01X1385540Y43998D01*
G03X1382457Y45275I-3083J-3083D01*
G01X1377679D01*
X1376103Y46851D01*
G01X1438800Y22500D02*
X1440120Y23820D01*
Y25923D01*
G03X1439839Y26602I-961J0D01*
G01X1439582Y26859D01*
G03X1438903Y27140I-679J-680D01*
G01X1436947D01*
G03X1435533Y26554I0J-1999D01*
G01X1433796Y24817D01*
G02X1430713Y23540I-3083J3083D01*
G01X1429054D01*
G03X1427877Y23094I-1J-1775D01*
G03X1427799Y23020I1182J-1324D01*
G02X1426544Y22500I-1255J1254D01*
G01X1425014D01*
G02X1423759Y23020I0J1774D01*
G03X1423681Y23094I-1260J-1250D01*
G03X1422504Y23540I-1176J-1329D01*
G01X1420754D01*
G03X1419577Y23094I-1J-1775D01*
G03X1419499Y23020I1182J-1324D01*
G02X1418244Y22500I-1255J1254D01*
G01X1416714D01*
G02X1415459Y23020I0J1774D01*
G03X1415381Y23094I-1260J-1250D01*
G03X1414204Y23540I-1176J-1329D01*
G01X1412554D01*
G03X1411377Y23094I-1J-1775D01*
G03X1411299Y23020I1182J-1324D01*
G02X1410044Y22500I-1255J1254D01*
G01X1408614D01*
G02X1407359Y23020I0J1774D01*
G03X1407334Y23044I-1241J-1268D01*
G01X1407279Y23093D01*
G03X1406104Y23540I-1177J-1327D01*
G01X1403488D01*
G02X1402074Y24126I0J1999D01*
G01X1401375Y24825D01*
G03X1399961Y25411I-1414J-1413D01*
G01X1399817D01*
G02X1398403Y25997I0J1999D01*
G01X1397539Y26861D01*
G02X1396953Y28275I1413J1414D01*
G01Y28419D01*
G03X1396367Y29833I-1999J0D01*
G01X1395503Y30697D01*
G03X1394089Y31283I-1414J-1413D01*
G01X1393845D01*
G02X1392431Y31869I0J1999D01*
G01X1391667Y32633D01*
G02X1391081Y34047I1413J1414D01*
G01Y34291D01*
G03X1390495Y35705I-1999J0D01*
G01X1389631Y36569D01*
G03X1388217Y37155I-1414J-1413D01*
G01X1388173D01*
G02X1386759Y37741I0J1999D01*
G01X1385795Y38705D01*
G02X1385209Y40119I1413J1414D01*
G01Y40163D01*
G03X1384623Y41577I-1999J0D01*
G01X1383871Y42329D01*
G03X1382457Y42915I-1414J-1413D01*
G01X1377679D01*
X1376103Y41339D01*
G54D29*
X335906Y59054D03*
X1205984D03*
G54D38*
X506024Y8268D03*
X688543D03*
X1376103D03*
X1558622D03*
G54D39*
X503859Y151650D03*
X1373938D03*
M02*
